G04 ================== begin FILE IDENTIFICATION RECORD ==================*
G04 Layout Name:  9052_F0T_PDB_Converter_Brick_F_V03_1208_1600.brd*
G04 Film Name:    pmt*
G04 File Format:  Gerber RS274X*
G04 File Origin:  Cadence Allegro 17.2-S081*
G04 Origin Date:  Wed Dec 21 09:54:59 2022*
G04 *
G04 Layer:  DRAWING FORMAT/TITLE_BLOCK_A*
G04 Layer:  VIA CLASS/PASTEMASK_TOP*
G04 Layer:  PIN/PASTEMASK_TOP*
G04 Layer:  PACKAGE GEOMETRY/PASTEMASK_TOP*
G04 Layer:  MANUFACTURING/PHOTOPLOT_OUTLINE*
G04 Layer:  DRAWING FORMAT/TITLE_BLOCK*
G04 Layer:  DRAWING FORMAT/TITLE_DATA_PMT*
G04 *
G04 Offset:    (0.00 0.00)*
G04 Mirror:    No*
G04 Mode:      Positive*
G04 Rotation:  0*
G04 FullContactRelief:  No*
G04 UndefLineWidth:     6.00*
G04 ================== end FILE IDENTIFICATION RECORD ====================*
%FSLAX25Y25*MOIN*%
%IR0*IPPOS*OFA0.00000B0.00000*MIA0B0*SFA1.00000B1.00000*%
%ADD13C,.03*%
%ADD82R,.13X.095*%
%AMMACRO66*
4,1,5,.07185,-.1063,
-.07185,-.1063,
-.07185,.09252,
-.05807,.1063,
.07185,.1063,
.07185,-.1063,
0.0*
%
%ADD66MACRO66*%
%ADD11C,.05*%
%ADD40C,.06*%
%ADD37C,.052*%
%ADD34C,.062*%
%ADD81R,.059X.134*%
%ADD76R,.099X.13*%
%ADD56R,.0848X.13*%
%ADD65C,.066*%
%ADD38C,.093*%
%ADD35C,.039*%
%ADD12R,.05X.05*%
%ADD41R,.06X.06*%
%ADD10C,.058*%
%ADD33R,.062X.062*%
%AMMACRO72*
4,1,8,-.05906,.02362,
.05906,.02362,
.05906,-.02362,
.00394,-.02362,
.00394,.01862,
-.00394,.01862,
-.00394,-.02362,
-.05906,-.02362,
-.05906,.02362,
0.0*
%
%ADD72MACRO72*%
%ADD64R,.066X.066*%
%ADD42R,.093X.093*%
%AMMACRO25*
4,1,28,-.00748,-.00052,
-.00984,-.00052,
-.00984,-.00603,
-.009782,-.006705,
-.009607,-.007359,
-.009321,-.007974,
-.008933,-.008529,
-.008455,-.009009,
-.0079,-.009398,
-.007286,-.009685,
-.006632,-.009861,
-.005957,-.00992,
-.00591,-.00992,
.00591,-.00992,
.006585,-.009869,
.007242,-.009701,
.007859,-.009421,
.008418,-.009039,
.008903,-.008565,
.009297,-.008015,
.009591,-.007404,
.009773,-.006751,
.00984,-.006077,
.00984,-.00603,
.00984,-.00052,
.00748,-.00052,
.00748,.00991,
-.00748,.00991,
-.00748,-.00052,
0.0*
%
%ADD25MACRO25*%
%AMMACRO55*
4,1,5,.01378,.00098,
.01378,-.00492,
-.01378,-.00492,
-.01378,.00492,
.00984,.00492,
.01378,.00098,
0.0*
%
%ADD55MACRO55*%
%AMMACRO49*
4,1,5,.00098,-.01378,
-.00492,-.01378,
-.00492,.01378,
.00492,.01378,
.00492,-.00984,
.00098,-.01378,
0.0*
%
%ADD49MACRO49*%
%AMMACRO23*
4,1,28,-.00052,.00748,
-.00052,.00984,
-.00603,.00984,
-.006705,.009782,
-.007359,.009607,
-.007974,.009321,
-.008529,.008933,
-.009009,.008455,
-.009398,.0079,
-.009685,.007286,
-.009861,.006632,
-.00992,.005957,
-.00992,.00591,
-.00992,-.00591,
-.009869,-.006585,
-.009701,-.007242,
-.009421,-.007859,
-.009039,-.008418,
-.008565,-.008903,
-.008015,-.009297,
-.007404,-.009591,
-.006751,-.009773,
-.006077,-.00984,
-.00603,-.00984,
-.00052,-.00984,
-.00052,-.00748,
.00991,-.00748,
.00991,.00748,
-.00052,.00748,
0.0*
%
%ADD23MACRO23*%
%AMMACRO24*
4,1,28,-.00748,.00051,
-.00984,.00051,
-.00984,.00602,
-.009782,.006695,
-.009607,.007349,
-.009321,.007964,
-.008933,.008519,
-.008455,.008998,
-.0079,.009388,
-.007287,.009675,
-.006632,.009851,
-.005958,.00991,
-.00591,.00991,
.00591,.00991,
.006585,.009859,
.007242,.009691,
.007859,.009411,
.008418,.009029,
.008903,.008555,
.009297,.008005,
.00959,.007394,
.009773,.006742,
.00984,.006068,
.00984,.00602,
.00984,.00051,
.00748,.00051,
.00748,-.00992,
-.00748,-.00992,
-.00748,.00051,
0.0*
%
%ADD24MACRO24*%
%AMMACRO53*
4,1,5,.01378,-.00098,
.01378,.00492,
-.01378,.00492,
-.01378,-.00492,
.00984,-.00492,
.01378,-.00098,
0.0*
%
%ADD53MACRO53*%
%AMMACRO48*
4,1,5,-.00098,-.01378,
.00492,-.01378,
.00492,.01378,
-.00492,.01378,
-.00492,-.00984,
-.00098,-.01378,
0.0*
%
%ADD48MACRO48*%
%AMMACRO22*
4,1,28,.00051,.00748,
.00051,.00984,
.00602,.00984,
.006695,.009782,
.007349,.009607,
.007964,.009321,
.008519,.008933,
.008998,.008455,
.009388,.0079,
.009675,.007287,
.009851,.006632,
.00991,.005958,
.00991,.00591,
.00991,-.00591,
.009859,-.006585,
.009691,-.007242,
.009411,-.007859,
.009029,-.008418,
.008555,-.008903,
.008005,-.009297,
.007394,-.00959,
.006742,-.009773,
.006068,-.00984,
.00602,-.00984,
.00051,-.00984,
.00051,-.00748,
-.00992,-.00748,
-.00992,.00748,
.00051,.00748,
0.0*
%
%ADD22MACRO22*%
%ADD77R,.11X.22*%
%ADD84R,.01X.02*%
%ADD70R,.03X.011*%
%ADD78O,.033X.012*%
%ADD69R,.011X.03*%
%ADD29R,.05X.01*%
%ADD20R,.032X.01*%
%ADD79O,.012X.033*%
%ADD30R,.01X.032*%
%ADD54R,.052X.01*%
%ADD73R,.032X.022*%
%ADD44R,.05X.04*%
%ADD50R,.036X.01*%
%ADD43R,.04X.05*%
%ADD15R,.02X.018*%
%ADD68R,.028X.011*%
%ADD28R,.018X.02*%
%ADD80C,.4*%
%ADD67R,.011X.028*%
%ADD61R,.063X.04*%
%ADD85R,.126X.27*%
%ADD59R,.04X.063*%
%ADD83R,.135X.128*%
%ADD45R,.032X.028*%
%ADD31C,.123*%
%ADD57R,.028X.024*%
%ADD16R,.028X.032*%
%ADD74R,.054X.044*%
%ADD71R,.015X.046*%
%ADD60R,.024X.028*%
%ADD62R,.062X.046*%
%ADD39R,.044X.054*%
%ADD32R,.046X.062*%
%ADD58R,.197X.116*%
%ADD63R,.116X.197*%
%ADD36R,.089X.085*%
%AMMACRO27*
4,1,28,.00748,.00052,
.00984,.00052,
.00984,.00603,
.009782,.006705,
.009607,.007359,
.009321,.007974,
.008933,.008529,
.008455,.009009,
.0079,.009398,
.007286,.009685,
.006632,.009861,
.005957,.00992,
.00591,.00992,
-.00591,.00992,
-.006585,.009869,
-.007242,.009701,
-.007859,.009421,
-.008418,.009039,
-.008903,.008565,
-.009297,.008015,
-.009591,.007404,
-.009773,.006751,
-.00984,.006077,
-.00984,.00603,
-.00984,.00052,
-.00748,.00052,
-.00748,-.00991,
.00748,-.00991,
.00748,.00052,
0.0*
%
%ADD27MACRO27*%
%AMMACRO18*
4,1,28,.00052,-.00748,
.00052,-.00984,
.00603,-.00984,
.006705,-.009782,
.007359,-.009607,
.007974,-.009321,
.008529,-.008933,
.009009,-.008455,
.009398,-.0079,
.009685,-.007286,
.009861,-.006632,
.00992,-.005957,
.00992,-.00591,
.00992,.00591,
.009869,.006585,
.009701,.007242,
.009421,.007859,
.009039,.008418,
.008565,.008903,
.008015,.009297,
.007404,.009591,
.006751,.009773,
.006077,.00984,
.00603,.00984,
.00052,.00984,
.00052,.00748,
-.00991,.00748,
-.00991,-.00748,
.00052,-.00748,
0.0*
%
%ADD18MACRO18*%
%ADD14R,.099X.067*%
%AMMACRO52*
4,1,5,-.01378,-.00098,
-.01378,.00492,
.01378,.00492,
.01378,-.00492,
-.00984,-.00492,
-.01378,-.00098,
0.0*
%
%ADD52MACRO52*%
%AMMACRO26*
4,1,28,.00748,-.00051,
.00984,-.00051,
.00984,-.00602,
.009782,-.006695,
.009607,-.007349,
.009321,-.007964,
.008933,-.008519,
.008455,-.008998,
.0079,-.009388,
.007287,-.009675,
.006632,-.009851,
.005958,-.00991,
.00591,-.00991,
-.00591,-.00991,
-.006585,-.009859,
-.007242,-.009691,
-.007859,-.009411,
-.008418,-.009029,
-.008903,-.008555,
-.009297,-.008005,
-.00959,-.007394,
-.009773,-.006742,
-.00984,-.006068,
-.00984,-.00602,
-.00984,-.00051,
-.00748,-.00051,
-.00748,.00992,
.00748,.00992,
.00748,-.00051,
0.0*
%
%ADD26MACRO26*%
%AMMACRO21*
4,1,5,.01673,-.00492,
.01673,.00492,
-.01673,.00492,
-.01673,-.00098,
-.0128,-.00492,
.01673,-.00492,
0.0*
%
%ADD21MACRO21*%
%AMMACRO17*
4,1,28,-.00051,-.00748,
-.00051,-.00984,
-.00602,-.00984,
-.006695,-.009782,
-.007349,-.009607,
-.007964,-.009321,
-.008519,-.008933,
-.008998,-.008455,
-.009388,-.0079,
-.009675,-.007287,
-.009851,-.006632,
-.00991,-.005958,
-.00991,-.00591,
-.00991,.00591,
-.009859,.006585,
-.009691,.007242,
-.009411,.007859,
-.009029,.008418,
-.008555,.008903,
-.008005,.009297,
-.007394,.00959,
-.006742,.009773,
-.006068,.00984,
-.00602,.00984,
-.00051,.00984,
-.00051,.00748,
.00992,.00748,
.00992,-.00748,
-.00051,-.00748,
0.0*
%
%ADD17MACRO17*%
%AMMACRO47*
4,1,5,-.00098,.01378,
.00492,.01378,
.00492,-.01378,
-.00492,-.01378,
-.00492,.00984,
-.00098,.01378,
0.0*
%
%ADD47MACRO47*%
%AMMACRO51*
4,1,5,-.01378,.00098,
-.01378,-.00492,
.01378,-.00492,
.01378,.00492,
-.00984,.00492,
-.01378,.00098,
0.0*
%
%ADD51MACRO51*%
%AMMACRO46*
4,1,5,.00098,.01378,
-.00492,.01378,
-.00492,-.01378,
.00492,-.01378,
.00492,.00984,
.00098,.01378,
0.0*
%
%ADD46MACRO46*%
%AMMACRO19*
4,1,8,.0246,.01821,
.0246,-.01821,
.01476,-.01821,
.01476,.00837,
-.01477,.00837,
-.01477,-.01821,
-.02461,-.01821,
-.02461,.01821,
.0246,.01821,
0.0*
%
%ADD19MACRO19*%
%ADD86C,.006*%
G75*
%LPD*%
G75*
G54D10*
X38780Y232598D03*
Y239291D03*
Y252598D03*
Y259291D03*
Y272598D03*
Y279291D03*
Y292598D03*
Y299291D03*
X48780Y232598D03*
Y239291D03*
Y252598D03*
Y259291D03*
Y272598D03*
Y279291D03*
Y292598D03*
Y299291D03*
G54D20*
X158588Y218326D03*
Y220294D03*
Y222263D03*
Y224232D03*
Y226200D03*
Y228168D03*
Y230137D03*
Y232106D03*
Y234074D03*
X169612D03*
Y232106D03*
Y230137D03*
Y228168D03*
Y226200D03*
Y224232D03*
Y222263D03*
Y220294D03*
G54D11*
X33780Y334724D03*
Y324724D03*
X38780Y319724D03*
Y329724D03*
Y339724D03*
X33780Y344724D03*
X38780Y349724D03*
X48780Y319724D03*
Y329724D03*
Y339724D03*
X43780Y314724D03*
Y324724D03*
Y334724D03*
X48780Y349724D03*
X43780Y344724D03*
G54D21*
X169513Y218326D03*
G54D30*
X162132Y235649D03*
X166068D03*
G54D12*
X33780Y314724D03*
G54D31*
X178819Y277204D03*
X193819D03*
X253819D03*
X268819D03*
X336299D03*
X351299D03*
X411299D03*
X426299D03*
X493780D03*
X508780D03*
X568780D03*
X583780D03*
X651261D03*
X666261D03*
X726261D03*
X741261D03*
G54D22*
X181384Y224820D03*
X181324Y242330D03*
X162041Y241140D03*
X181324Y231330D03*
Y220830D03*
Y238330D03*
X704484Y32000D03*
X697484D03*
X697519Y36695D03*
X697484Y27000D03*
X704519Y36695D03*
X755984Y27500D03*
Y68500D03*
X1041584Y193700D03*
X1044038Y143267D03*
X1089484Y103000D03*
X1099952Y160413D03*
X1100016Y143144D03*
X1099984Y147500D03*
X1099952Y156099D03*
Y151856D03*
X1112984Y88000D03*
X1129652Y142556D03*
X1103484Y173500D03*
X1128977Y192756D03*
X1133184Y138457D03*
X1174984Y111500D03*
G54D40*
X268000Y220315D03*
X312500D03*
X357000D03*
X428500D03*
X472500D03*
X516500D03*
X578500D03*
X622500D03*
X666500D03*
X735981D03*
X779981D03*
X823981D03*
G54D13*
X92110Y300900D03*
X85000Y307310D03*
X77770Y313960D03*
X106230Y287950D03*
X99810Y294370D03*
X144900Y224500D03*
X141664Y239573D03*
X178265Y247712D03*
X171374Y251923D03*
X660100Y39900D03*
X711500Y61300D03*
X792000Y358000D03*
X833500Y268575D03*
X816000Y270525D03*
X827602Y283500D03*
X836500Y302500D03*
X814050Y341450D03*
X819500Y318500D03*
X831750Y318250D03*
X813100Y368600D03*
X827000Y352500D03*
X843500Y268575D03*
X853500D03*
X845000Y303000D03*
X848500Y335800D03*
X840000Y337500D03*
Y363000D03*
Y345500D03*
X843843Y354342D03*
X849000Y399000D03*
X870000Y304525D03*
X880000D03*
X870000Y312788D03*
X880000Y312855D03*
X875000Y347273D03*
X905941Y320366D03*
X916260Y355000D03*
X923740Y345500D03*
X940000Y283800D03*
X935516Y361075D03*
X933357Y344843D03*
X933196Y353360D03*
X1028940Y182130D03*
X1034290Y197990D03*
X1050220Y126510D03*
X1053505Y144080D03*
X1053000Y136500D03*
X1064500Y166000D03*
X1059500Y175500D03*
X1054000Y181000D03*
X1066000Y175500D03*
X1062500Y181000D03*
X1091000Y89000D03*
X1094500Y103000D03*
X1077400Y141300D03*
X1115500Y97500D03*
X1121000Y94500D03*
X1127148Y147566D03*
X1118000Y146000D03*
X1106500Y155000D03*
X1105000Y147500D03*
X1112500Y151000D03*
X1105500Y161779D03*
X1110925Y187500D03*
X1110800Y170000D03*
X1131088Y186912D03*
X1108500Y176000D03*
X1105170Y182630D03*
X1153845Y161098D03*
X1158750Y144750D03*
X1137808Y187588D03*
X1135000Y220600D03*
X1136600Y228060D03*
X1189000Y248500D03*
Y266000D03*
X1190500Y420000D03*
Y402500D03*
X1230000Y458000D03*
X1248000D03*
G54D14*
X118126Y258500D03*
X133874D03*
G54D32*
X181839Y503500D03*
X170239D03*
X181839Y512500D03*
X170239D03*
X229839D03*
X218239D03*
X229839Y503500D03*
X218239D03*
X266239D03*
Y512500D03*
X277839Y503500D03*
Y512500D03*
X327719Y503500D03*
Y512500D03*
X339319Y503500D03*
Y512500D03*
X387319D03*
X375719D03*
X387319Y503500D03*
X375719D03*
X435319D03*
X423719D03*
X435319Y512500D03*
X423719D03*
X496800D03*
X485200D03*
X496800Y503500D03*
X485200D03*
X533200D03*
Y512500D03*
X544800Y503500D03*
Y512500D03*
X592800D03*
X581200D03*
X592800Y503500D03*
X581200D03*
X654281Y512500D03*
X642681D03*
X654281Y503500D03*
X642681D03*
X702281Y512500D03*
X690681D03*
X702281Y503500D03*
X690681D03*
X738681Y512500D03*
Y503500D03*
X750281Y512500D03*
Y503500D03*
G54D50*
X703346Y49268D03*
Y45332D03*
Y47300D03*
X696654Y45332D03*
Y49268D03*
G54D23*
X178417Y224820D03*
X178357Y242330D03*
X159074Y241140D03*
X178357Y231330D03*
Y220830D03*
Y238330D03*
X701517Y32000D03*
X694517D03*
X694552Y36695D03*
X694517Y27000D03*
X701552Y36695D03*
X753017Y27500D03*
Y68500D03*
X1041071Y143267D03*
X1038617Y193700D03*
X1086517Y103000D03*
X1096985Y160413D03*
X1097049Y143144D03*
X1097017Y147500D03*
X1096985Y156099D03*
Y151856D03*
X1100517Y173500D03*
X1110017Y88000D03*
X1130217Y138457D03*
X1126685Y142556D03*
X1126010Y192756D03*
X1172017Y111500D03*
G54D41*
X268000Y240000D03*
X312500D03*
X357000D03*
X428500D03*
X472500D03*
X516500D03*
X578500D03*
X622500D03*
X666500D03*
X735981D03*
X779981D03*
X823981D03*
G54D51*
X703740Y51237D03*
G54D60*
X830630Y329000D03*
X834370D03*
G54D15*
X153180Y215785D03*
Y218935D03*
X141840Y234905D03*
Y231755D03*
X181271Y212651D03*
Y209501D03*
X691400Y50875D03*
Y47725D03*
G54D24*
X170040Y245314D03*
X710000Y41984D03*
X706000Y59484D03*
X803500Y264984D03*
X792354Y265093D03*
X782354D03*
X1041500Y188984D03*
X1091000Y96984D03*
X1095100D03*
X1108500Y141984D03*
X1110000Y195484D03*
X1118000D03*
X1106000D03*
X1114000D03*
X1122000D03*
X1133000D03*
G54D42*
X253819Y477204D03*
X411299D03*
X568780D03*
X726261D03*
G54D33*
X165539Y539000D03*
X213539D03*
X261539D03*
X323019D03*
X371019D03*
X419019D03*
X480500D03*
X528500D03*
X576500D03*
X637981D03*
X685981D03*
X733981D03*
G54D52*
X703740Y43363D03*
G54D16*
X152200Y241200D03*
Y235400D03*
X147000Y241200D03*
Y235400D03*
X1064500Y276242D03*
Y270442D03*
Y323742D03*
Y317942D03*
Y359642D03*
Y365442D03*
Y418742D03*
Y412942D03*
Y466242D03*
Y460442D03*
Y513742D03*
Y507942D03*
G54D61*
X840000Y369701D03*
Y382299D03*
X1155000Y193201D03*
Y205799D03*
G54D43*
X293500Y204500D03*
X286500D03*
X293500Y196500D03*
X286500D03*
X329500Y204500D03*
Y196500D03*
X315000Y204500D03*
X308000D03*
X315000Y196500D03*
X308000D03*
X358000Y204500D03*
X351000D03*
X358000Y196500D03*
X351000D03*
X336500Y204500D03*
Y196500D03*
X379500Y204500D03*
X372500D03*
X379500Y197000D03*
X372500D03*
X422500Y204500D03*
X415500D03*
X422500Y197000D03*
X415500D03*
X401000Y204500D03*
X394000D03*
X401000Y197000D03*
X394000D03*
X594000Y204000D03*
Y196500D03*
X622500D03*
X615500D03*
X622500Y204000D03*
X615500D03*
X601000D03*
Y196500D03*
X658500Y204000D03*
Y196500D03*
X644000Y204000D03*
X637000D03*
X644000Y196500D03*
X637000D03*
X687000Y204000D03*
X680000D03*
X687000Y196500D03*
X680000D03*
X665500Y204000D03*
Y196500D03*
X708490Y204000D03*
X701490D03*
X708490Y196500D03*
X701490D03*
X729990Y204000D03*
X722990D03*
X729990Y196500D03*
X722990D03*
X758000Y43000D03*
X751000D03*
X758000Y34500D03*
X751000D03*
X758000Y60000D03*
X751000D03*
X758000Y51500D03*
X751000D03*
X1144585Y145913D03*
X1151585D03*
G54D70*
X1025168Y153909D03*
Y155877D03*
Y157846D03*
Y159814D03*
Y161783D03*
Y169657D03*
Y171625D03*
X1051940Y159814D03*
Y157846D03*
Y155877D03*
Y153909D03*
Y171625D03*
Y169657D03*
Y167688D03*
Y165720D03*
Y163751D03*
Y161783D03*
G54D25*
X170040Y242347D03*
X710000Y39017D03*
X706000Y56517D03*
X803500Y262017D03*
X792354Y262126D03*
X782354D03*
X1041500Y186017D03*
X1091000Y94017D03*
X1095100D03*
X1108500Y139017D03*
X1110000Y192517D03*
X1118000D03*
X1106000D03*
X1114000D03*
X1122000D03*
X1133000D03*
G54D34*
X185224Y539000D03*
X233224D03*
X281224D03*
X342704D03*
X390704D03*
X438704D03*
X500185D03*
X548185D03*
X596185D03*
X657666D03*
X705666D03*
X753666D03*
G54D17*
X178356Y216830D03*
X687016Y36500D03*
Y32500D03*
X698616Y57800D03*
X1019516Y98000D03*
Y118000D03*
X1041070Y131267D03*
Y139267D03*
Y135267D03*
X1048070Y131267D03*
X1096516Y188000D03*
X1093016Y173500D03*
X1096516Y179500D03*
X1096484Y183599D03*
X1123016Y138457D03*
X1177927Y346750D03*
X1178016Y489250D03*
G54D26*
X166040Y242346D03*
X710000Y46516D03*
X787354Y262125D03*
X1048000Y135516D03*
X1067000Y186016D03*
X1053500D03*
X1058000D03*
X1062500D03*
X1104500Y139016D03*
X1112500D03*
G54D62*
X849000Y370200D03*
Y381800D03*
X867000Y370200D03*
Y381800D03*
X858000Y370200D03*
Y381800D03*
X876000Y370200D03*
Y381800D03*
X895000Y370200D03*
Y381800D03*
X885500Y370200D03*
Y381800D03*
X904500Y370200D03*
Y381800D03*
X914000Y370200D03*
Y381800D03*
X923500Y370200D03*
Y381800D03*
X933000Y370200D03*
Y381800D03*
X942500Y370200D03*
Y381800D03*
X952000Y370200D03*
Y381800D03*
X1025000Y131200D03*
Y142800D03*
X1068554Y127467D03*
Y139067D03*
X1161200Y160200D03*
Y171800D03*
X1140641Y205399D03*
Y193799D03*
G54D71*
X1070715Y150749D03*
Y174785D03*
X1073274Y150749D03*
X1075834D03*
X1078393D03*
X1073274Y174785D03*
X1075834D03*
X1078393D03*
G54D80*
X1240158Y57480D03*
Y521260D03*
G54D44*
X653700Y52700D03*
Y45700D03*
X677400Y52700D03*
Y45700D03*
X685300Y52700D03*
Y45700D03*
X669500Y52700D03*
Y45700D03*
X661600Y52700D03*
Y45700D03*
X1130368Y228060D03*
X1121568Y224060D03*
Y232060D03*
G54D53*
X696260Y43363D03*
G54D35*
X201000Y20500D03*
X892110Y81122D03*
X1176815Y555392D03*
G54D18*
X181323Y216830D03*
X689983Y36500D03*
Y32500D03*
X701583Y57800D03*
X1022483Y98000D03*
Y118000D03*
X1044037Y131267D03*
X1051037D03*
X1044037Y139267D03*
Y135267D03*
X1099483Y188000D03*
X1095983Y173500D03*
X1099483Y179500D03*
X1099451Y183599D03*
X1125983Y138457D03*
X1180894Y346750D03*
X1180983Y489250D03*
G54D27*
X166040Y245313D03*
X710000Y49483D03*
X787354Y265092D03*
X1048000Y138483D03*
X1067000Y188983D03*
X1053500D03*
X1058000D03*
X1062500D03*
X1104500Y141983D03*
X1112500D03*
G54D36*
X197400Y214054D03*
Y233346D03*
G54D63*
X861622Y513070D03*
X904200D03*
G54D45*
X641300Y45200D03*
X647100D03*
X1039100Y126500D03*
X1044900D03*
X1101400Y168500D03*
X1095600D03*
X1110100Y83000D03*
X1115900D03*
X1170600Y105500D03*
X1176400D03*
X1174311Y328750D03*
X1168511D03*
X1184511D03*
X1190311D03*
Y335750D03*
X1184511D03*
X1168511D03*
X1174311D03*
Y341750D03*
X1168511D03*
X1184511D03*
X1190311D03*
X1184600Y484250D03*
X1190400D03*
X1174400D03*
X1168600D03*
X1174400Y471250D03*
X1168600D03*
X1184600D03*
X1190400D03*
X1174400Y478250D03*
X1168600D03*
X1184600D03*
X1190400D03*
G54D54*
X697441Y47300D03*
G54D72*
X1076164Y250442D03*
Y270442D03*
Y297942D03*
Y317942D03*
Y345442D03*
Y365442D03*
Y392942D03*
Y412942D03*
Y440442D03*
Y487942D03*
Y460442D03*
Y507942D03*
G54D81*
X1138178Y166699D03*
G54D19*
X164101Y216997D03*
G54D46*
X700984Y41591D03*
G54D28*
X162132Y249140D03*
X158982D03*
X162132Y245160D03*
X158982D03*
X239575Y243000D03*
X236425D03*
X239575Y247500D03*
X236425D03*
X395575Y242500D03*
X392425D03*
X395575Y247000D03*
X392425D03*
X549075Y243500D03*
X545925D03*
X549075Y248000D03*
X545925D03*
X645575Y33000D03*
X642425D03*
X645575Y37000D03*
X642425D03*
X706556Y243500D03*
X703406D03*
X706556Y248000D03*
X703406D03*
X1108590Y224241D03*
X1111740D03*
D03*
X1114890D03*
X1111656Y231741D03*
X1114806D03*
X1111656D03*
X1108506D03*
G54D73*
X1100276Y93760D03*
Y101240D03*
X1109724D03*
Y97500D03*
Y93760D03*
G54D55*
X696260Y51237D03*
G54D64*
X1011000Y98000D03*
X1151000Y90400D03*
G54D37*
X208071Y267204D03*
X200197D03*
X215945D03*
X231693D03*
X223819D03*
X239567D03*
X247441D03*
X357677D03*
X365551D03*
X373425D03*
X389173D03*
X381299D03*
X404921D03*
X397047D03*
X523032D03*
X515158D03*
X530906D03*
X538780D03*
X546654D03*
X562402D03*
X554528D03*
X680513D03*
X672639D03*
X688387D03*
X704135D03*
X696261D03*
X712009D03*
X719883D03*
G54D82*
X1183561Y130467D03*
Y156451D03*
G54D47*
X699016Y41591D03*
G54D74*
X1089772Y132065D03*
Y139545D03*
X1132941Y131996D03*
Y124516D03*
X1123441Y131996D03*
Y124516D03*
X1152587Y131678D03*
Y139158D03*
X1166000Y140760D03*
Y148240D03*
G54D83*
X1183100Y176094D03*
Y212906D03*
G54D29*
X164100Y232499D03*
Y228956D03*
Y225413D03*
Y221869D03*
G54D38*
X193819Y477204D03*
X223819D03*
X351299D03*
X381299D03*
X508780D03*
X538780D03*
X666261D03*
X696261D03*
G54D65*
X1011000Y118000D03*
Y108000D03*
X1161000Y90400D03*
X1171000D03*
G54D56*
X717985Y51000D03*
X741015D03*
G36*
G01X1100377Y275009D02*
X1106283D01*
Y268316D01*
X1103580D01*
Y267529D01*
X1106283D01*
Y260836D01*
X1103580D01*
Y260048D01*
X1106283D01*
Y253355D01*
X1103580D01*
Y252568D01*
X1106283D01*
Y249472D01*
X1112582D01*
Y252568D01*
X1115285D01*
Y253355D01*
X1112582D01*
Y260048D01*
X1115285D01*
Y260836D01*
X1112582D01*
Y267529D01*
X1115285D01*
Y268316D01*
X1112582D01*
Y275009D01*
X1118487D01*
Y268316D01*
X1115785D01*
Y267529D01*
X1118487D01*
Y260836D01*
X1115785D01*
Y260048D01*
X1118487D01*
Y253355D01*
X1115785D01*
Y252568D01*
X1118487D01*
Y249472D01*
X1124787D01*
Y252765D01*
X1128769D01*
Y253946D01*
X1124787D01*
Y259851D01*
X1128769D01*
Y261033D01*
X1124787D01*
Y266938D01*
X1128769D01*
Y268119D01*
X1124787D01*
Y274025D01*
X1128769D01*
Y275206D01*
X1124787D01*
Y281111D01*
X1133251D01*
Y275206D01*
X1129269D01*
Y274025D01*
X1133251D01*
Y268119D01*
X1129269D01*
Y266938D01*
X1133251D01*
Y261033D01*
X1129269D01*
Y259851D01*
X1133251D01*
Y253946D01*
X1129269D01*
Y252765D01*
X1133251D01*
Y246859D01*
X1129269D01*
Y245678D01*
X1133251D01*
Y239773D01*
X1124787D01*
Y245678D01*
X1128769D01*
Y246859D01*
X1124787D01*
Y248972D01*
X1118487D01*
Y245875D01*
X1112582D01*
Y248972D01*
X1106283D01*
Y245875D01*
X1100377D01*
Y252568D01*
X1103080D01*
Y253355D01*
X1100377D01*
Y260048D01*
X1103080D01*
Y260836D01*
X1100377D01*
Y267529D01*
X1103080D01*
Y268316D01*
X1100377D01*
Y275009D01*
G37*
G36*
G01Y322509D02*
X1106283D01*
Y315816D01*
X1103580D01*
Y315029D01*
X1106283D01*
Y308336D01*
X1103580D01*
Y307548D01*
X1106283D01*
Y300855D01*
X1103580D01*
Y300068D01*
X1106283D01*
Y296972D01*
X1112582D01*
Y300068D01*
X1115285D01*
Y300855D01*
X1112582D01*
Y307548D01*
X1115285D01*
Y308336D01*
X1112582D01*
Y315029D01*
X1115285D01*
Y315816D01*
X1112582D01*
Y322509D01*
X1118487D01*
Y315816D01*
X1115785D01*
Y315029D01*
X1118487D01*
Y308336D01*
X1115785D01*
Y307548D01*
X1118487D01*
Y300855D01*
X1115785D01*
Y300068D01*
X1118487D01*
Y296972D01*
X1124787D01*
Y300265D01*
X1128769D01*
Y301446D01*
X1124787D01*
Y307351D01*
X1128769D01*
Y308533D01*
X1124787D01*
Y314438D01*
X1128769D01*
Y315619D01*
X1124787D01*
Y321525D01*
X1128769D01*
Y322706D01*
X1124787D01*
Y328611D01*
X1133251D01*
Y322706D01*
X1129269D01*
Y321525D01*
X1133251D01*
Y315619D01*
X1129269D01*
Y314438D01*
X1133251D01*
Y308533D01*
X1129269D01*
Y307351D01*
X1133251D01*
Y301446D01*
X1129269D01*
Y300265D01*
X1133251D01*
Y294359D01*
X1129269D01*
Y293178D01*
X1133251D01*
Y287273D01*
X1124787D01*
Y293178D01*
X1128769D01*
Y294359D01*
X1124787D01*
Y296472D01*
X1118487D01*
Y293375D01*
X1112582D01*
Y296472D01*
X1106283D01*
Y293375D01*
X1100377D01*
Y300068D01*
X1103080D01*
Y300855D01*
X1100377D01*
Y307548D01*
X1103080D01*
Y308336D01*
X1100377D01*
Y315029D01*
X1103080D01*
Y315816D01*
X1100377D01*
Y322509D01*
G37*
G36*
G01Y370009D02*
X1106283D01*
Y363316D01*
X1103580D01*
Y362529D01*
X1106283D01*
Y355836D01*
X1103580D01*
Y355048D01*
X1106283D01*
Y348355D01*
X1103580D01*
Y347568D01*
X1106283D01*
Y344472D01*
X1112582D01*
Y347568D01*
X1115285D01*
Y348355D01*
X1112582D01*
Y355048D01*
X1115285D01*
Y355836D01*
X1112582D01*
Y362529D01*
X1115285D01*
Y363316D01*
X1112582D01*
Y370009D01*
X1118487D01*
Y363316D01*
X1115785D01*
Y362529D01*
X1118487D01*
Y355836D01*
X1115785D01*
Y355048D01*
X1118487D01*
Y348355D01*
X1115785D01*
Y347568D01*
X1118487D01*
Y344472D01*
X1124787D01*
Y347765D01*
X1128769D01*
Y348946D01*
X1124787D01*
Y354851D01*
X1128769D01*
Y356033D01*
X1124787D01*
Y361938D01*
X1128769D01*
Y363119D01*
X1124787D01*
Y369025D01*
X1128769D01*
Y370206D01*
X1124787D01*
Y376111D01*
X1133251D01*
Y370206D01*
X1129269D01*
Y369025D01*
X1133251D01*
Y363119D01*
X1129269D01*
Y361938D01*
X1133251D01*
Y356033D01*
X1129269D01*
Y354851D01*
X1133251D01*
Y348946D01*
X1129269D01*
Y347765D01*
X1133251D01*
Y341859D01*
X1129269D01*
Y340678D01*
X1133251D01*
Y334773D01*
X1124787D01*
Y340678D01*
X1128769D01*
Y341859D01*
X1124787D01*
Y343972D01*
X1118487D01*
Y340875D01*
X1112582D01*
Y343972D01*
X1106283D01*
Y340875D01*
X1100377D01*
Y347568D01*
X1103080D01*
Y348355D01*
X1100377D01*
Y355048D01*
X1103080D01*
Y355836D01*
X1100377D01*
Y362529D01*
X1103080D01*
Y363316D01*
X1100377D01*
Y370009D01*
G37*
G36*
G01Y417509D02*
X1106283D01*
Y410816D01*
X1103580D01*
Y410029D01*
X1106283D01*
Y403336D01*
X1103580D01*
Y402548D01*
X1106283D01*
Y395855D01*
X1103580D01*
Y395068D01*
X1106283D01*
Y391972D01*
X1112582D01*
Y395068D01*
X1115285D01*
Y395855D01*
X1112582D01*
Y402548D01*
X1115285D01*
Y403336D01*
X1112582D01*
Y410029D01*
X1115285D01*
Y410816D01*
X1112582D01*
Y417509D01*
X1118487D01*
Y410816D01*
X1115785D01*
Y410029D01*
X1118487D01*
Y403336D01*
X1115785D01*
Y402548D01*
X1118487D01*
Y395855D01*
X1115785D01*
Y395068D01*
X1118487D01*
Y391972D01*
X1124787D01*
Y395265D01*
X1128769D01*
Y396446D01*
X1124787D01*
Y402351D01*
X1128769D01*
Y403533D01*
X1124787D01*
Y409438D01*
X1128769D01*
Y410619D01*
X1124787D01*
Y416525D01*
X1128769D01*
Y417706D01*
X1124787D01*
Y423611D01*
X1133251D01*
Y417706D01*
X1129269D01*
Y416525D01*
X1133251D01*
Y410619D01*
X1129269D01*
Y409438D01*
X1133251D01*
Y403533D01*
X1129269D01*
Y402351D01*
X1133251D01*
Y396446D01*
X1129269D01*
Y395265D01*
X1133251D01*
Y389359D01*
X1129269D01*
Y388178D01*
X1133251D01*
Y382273D01*
X1124787D01*
Y388178D01*
X1128769D01*
Y389359D01*
X1124787D01*
Y391472D01*
X1118487D01*
Y388375D01*
X1112582D01*
Y391472D01*
X1106283D01*
Y388375D01*
X1100377D01*
Y395068D01*
X1103080D01*
Y395855D01*
X1100377D01*
Y402548D01*
X1103080D01*
Y403336D01*
X1100377D01*
Y410029D01*
X1103080D01*
Y410816D01*
X1100377D01*
Y417509D01*
G37*
G36*
G01Y465009D02*
X1106283D01*
Y458316D01*
X1103580D01*
Y457529D01*
X1106283D01*
Y450836D01*
X1103580D01*
Y450048D01*
X1106283D01*
Y443355D01*
X1103580D01*
Y442568D01*
X1106283D01*
Y439472D01*
X1112582D01*
Y442568D01*
X1115285D01*
Y443355D01*
X1112582D01*
Y450048D01*
X1115285D01*
Y450836D01*
X1112582D01*
Y457529D01*
X1115285D01*
Y458316D01*
X1112582D01*
Y465009D01*
X1118487D01*
Y458316D01*
X1115785D01*
Y457529D01*
X1118487D01*
Y450836D01*
X1115785D01*
Y450048D01*
X1118487D01*
Y443355D01*
X1115785D01*
Y442568D01*
X1118487D01*
Y439472D01*
X1124787D01*
Y442765D01*
X1128769D01*
Y443946D01*
X1124787D01*
Y449851D01*
X1128769D01*
Y451033D01*
X1124787D01*
Y456938D01*
X1128769D01*
Y458119D01*
X1124787D01*
Y464025D01*
X1128769D01*
Y465206D01*
X1124787D01*
Y471111D01*
X1133251D01*
Y465206D01*
X1129269D01*
Y464025D01*
X1133251D01*
Y458119D01*
X1129269D01*
Y456938D01*
X1133251D01*
Y451033D01*
X1129269D01*
Y449851D01*
X1133251D01*
Y443946D01*
X1129269D01*
Y442765D01*
X1133251D01*
Y436859D01*
X1129269D01*
Y435678D01*
X1133251D01*
Y429773D01*
X1124787D01*
Y435678D01*
X1128769D01*
Y436859D01*
X1124787D01*
Y438972D01*
X1118487D01*
Y435875D01*
X1112582D01*
Y438972D01*
X1106283D01*
Y435875D01*
X1100377D01*
Y442568D01*
X1103080D01*
Y443355D01*
X1100377D01*
Y450048D01*
X1103080D01*
Y450836D01*
X1100377D01*
Y457529D01*
X1103080D01*
Y458316D01*
X1100377D01*
Y465009D01*
G37*
G36*
G01Y512509D02*
X1106283D01*
Y505816D01*
X1103580D01*
Y505029D01*
X1106283D01*
Y498336D01*
X1103580D01*
Y497548D01*
X1106283D01*
Y490855D01*
X1103580D01*
Y490068D01*
X1106283D01*
Y486972D01*
X1112582D01*
Y490068D01*
X1115285D01*
Y490855D01*
X1112582D01*
Y497548D01*
X1115285D01*
Y498336D01*
X1112582D01*
Y505029D01*
X1115285D01*
Y505816D01*
X1112582D01*
Y512509D01*
X1118487D01*
Y505816D01*
X1115785D01*
Y505029D01*
X1118487D01*
Y498336D01*
X1115785D01*
Y497548D01*
X1118487D01*
Y490855D01*
X1115785D01*
Y490068D01*
X1118487D01*
Y486972D01*
X1124787D01*
Y490265D01*
X1128769D01*
Y491446D01*
X1124787D01*
Y497351D01*
X1128769D01*
Y498533D01*
X1124787D01*
Y504438D01*
X1128769D01*
Y505619D01*
X1124787D01*
Y511525D01*
X1128769D01*
Y512706D01*
X1124787D01*
Y518611D01*
X1133251D01*
Y512706D01*
X1129269D01*
Y511525D01*
X1133251D01*
Y505619D01*
X1129269D01*
Y504438D01*
X1133251D01*
Y498533D01*
X1129269D01*
Y497351D01*
X1133251D01*
Y491446D01*
X1129269D01*
Y490265D01*
X1133251D01*
Y484359D01*
X1129269D01*
Y483178D01*
X1133251D01*
Y477273D01*
X1124787D01*
Y483178D01*
X1128769D01*
Y484359D01*
X1124787D01*
Y486472D01*
X1118487D01*
Y483375D01*
X1112582D01*
Y486472D01*
X1106283D01*
Y483375D01*
X1100377D01*
Y490068D01*
X1103080D01*
Y490855D01*
X1100377D01*
Y497548D01*
X1103080D01*
Y498336D01*
X1100377D01*
Y505029D01*
X1103080D01*
Y505816D01*
X1100377D01*
Y512509D01*
G37*
G54D39*
X241740Y237000D03*
X234260D03*
X390260Y236500D03*
X397740D03*
X551240Y237500D03*
X543760D03*
X708721D03*
X701241D03*
X1028294Y188767D03*
X1020814D03*
X1028294Y199267D03*
X1020814D03*
X1083440Y95400D03*
X1075960D03*
X1096260Y82500D03*
X1098740Y199500D03*
X1091260D03*
X1103740Y82500D03*
G54D57*
X797854Y262239D03*
Y265979D03*
X809500Y262130D03*
Y265870D03*
G54D84*
X1176593Y307942D03*
X1182709D03*
X1176682Y450442D03*
X1182798D03*
G54D48*
X699016Y53009D03*
G54D66*
X1041999Y162767D03*
G54D58*
X807315Y424566D03*
Y467144D03*
X863917Y424566D03*
Y467144D03*
G54D85*
X1170793Y307942D03*
X1188509D03*
X1170882Y450442D03*
X1188598D03*
G54D67*
X1027727Y149281D03*
Y176253D03*
X1049381Y149281D03*
Y176253D03*
G54D49*
X700984Y53009D03*
G54D76*
X1077614Y545500D03*
X1104386D03*
G54D86*
G01X-297025Y-1013390D02*
Y1828909D01*
X3691357D01*
Y-1013390D01*
X-297025D01*
G01X4093Y-769672D02*
Y-844672D01*
X504093D01*
Y-769672D01*
X4093D01*
G01X16093Y-834672D02*
Y-839672D01*
G01X14636Y-834672D02*
X17550D01*
G01X22460Y-839672D02*
X19926D01*
Y-834672D01*
X22460D01*
G01X21446Y-837089D02*
X19926D01*
G01X25026Y-834672D02*
Y-839672D01*
X27560D01*
G01X31393Y-839839D02*
X31266Y-839755D01*
Y-839589D01*
X31393Y-839505D01*
X31520Y-839589D01*
Y-839755D01*
X31393Y-839839D01*
G01Y-837589D02*
X31266Y-837505D01*
Y-837339D01*
X31393Y-837255D01*
X31520Y-837339D01*
Y-837505D01*
X31393Y-837589D01*
G01X36176Y-841339D02*
X35543Y-840505D01*
X35226Y-839672D01*
Y-836339D01*
X35543Y-835505D01*
X36176Y-834672D01*
G01X41593D02*
X41086Y-834839D01*
X40706Y-835255D01*
X40453Y-835755D01*
X40263Y-836422D01*
X40200Y-837172D01*
X40263Y-837922D01*
X40453Y-838589D01*
X40706Y-839089D01*
X41086Y-839505D01*
X41593Y-839672D01*
X42100Y-839505D01*
X42480Y-839089D01*
X42733Y-838589D01*
X42923Y-837922D01*
X42986Y-837172D01*
X42923Y-836422D01*
X42733Y-835755D01*
X42480Y-835255D01*
X42100Y-834839D01*
X41593Y-834672D01*
G01X45300Y-838672D02*
X45680Y-839255D01*
X46186Y-839589D01*
X46756Y-839672D01*
X47263Y-839589D01*
X47770Y-839172D01*
X48086Y-838672D01*
X48150Y-838172D01*
X48023Y-837589D01*
X47580Y-837172D01*
X47136Y-837005D01*
X46566D01*
G01X47136D02*
X47516Y-836755D01*
X47833Y-836339D01*
X47960Y-835839D01*
X47833Y-835339D01*
X47516Y-834922D01*
X46946Y-834672D01*
X46376Y-834755D01*
X45806Y-835089D01*
G01X52110Y-841339D02*
X52743Y-840505D01*
X53060Y-839672D01*
Y-836339D01*
X52743Y-835505D01*
X52110Y-834672D01*
G01X55500Y-838672D02*
X55880Y-839255D01*
X56386Y-839589D01*
X56956Y-839672D01*
X57463Y-839589D01*
X57970Y-839172D01*
X58286Y-838672D01*
X58350Y-838172D01*
X58223Y-837589D01*
X57780Y-837172D01*
X57336Y-837005D01*
X56766D01*
G01X57336D02*
X57716Y-836755D01*
X58033Y-836339D01*
X58160Y-835839D01*
X58033Y-835339D01*
X57716Y-834922D01*
X57146Y-834672D01*
X56576Y-834755D01*
X56006Y-835089D01*
G01X60790Y-835505D02*
X61170Y-835005D01*
X61613Y-834755D01*
X62120Y-834672D01*
X62753Y-834839D01*
X63196Y-835255D01*
X63323Y-835755D01*
X63260Y-836255D01*
X63006Y-836672D01*
X61740Y-837505D01*
X61170Y-838089D01*
X60790Y-838922D01*
X60663Y-839672D01*
X63323D01*
G01X66966D02*
X67093Y-838589D01*
X67283Y-837672D01*
X67536Y-836839D01*
X67853Y-835922D01*
X68360Y-834672D01*
X65826D01*
G01X71370Y-838005D02*
X73016D01*
G01X76090Y-835505D02*
X76470Y-835005D01*
X76913Y-834755D01*
X77420Y-834672D01*
X78053Y-834839D01*
X78496Y-835255D01*
X78623Y-835755D01*
X78560Y-836255D01*
X78306Y-836672D01*
X77040Y-837505D01*
X76470Y-838089D01*
X76090Y-838922D01*
X75963Y-839672D01*
X78623D01*
G01X81000Y-838672D02*
X81380Y-839255D01*
X81886Y-839589D01*
X82456Y-839672D01*
X82963Y-839589D01*
X83470Y-839172D01*
X83786Y-838672D01*
X83850Y-838172D01*
X83723Y-837589D01*
X83280Y-837172D01*
X82836Y-837005D01*
X82266D01*
G01X82836D02*
X83216Y-836755D01*
X83533Y-836339D01*
X83660Y-835839D01*
X83533Y-835339D01*
X83216Y-834922D01*
X82646Y-834672D01*
X82076Y-834755D01*
X81506Y-835089D01*
G01X88253Y-839672D02*
Y-834672D01*
X85910Y-838255D01*
X89076D01*
G01X91200Y-838922D02*
X91580Y-839339D01*
X92023Y-839589D01*
X92593Y-839672D01*
X93163Y-839505D01*
X93606Y-839172D01*
X93923Y-838589D01*
X93986Y-837922D01*
X93860Y-837255D01*
X93543Y-836839D01*
X93100Y-836505D01*
X92656Y-836422D01*
X92213Y-836505D01*
X91643Y-836839D01*
X91833Y-834672D01*
X93543D01*
G01X101590Y-839672D02*
Y-834672D01*
X103996D01*
G01X103110Y-837089D02*
X101590D01*
G01X106310Y-839672D02*
X107893Y-834672D01*
X109476Y-839672D01*
G01X108906Y-837922D02*
X106880D01*
G01X111663Y-839672D02*
X114323Y-834672D01*
G01X111663D02*
X114323Y-839672D01*
G01X118093Y-839839D02*
X117966Y-839755D01*
Y-839589D01*
X118093Y-839505D01*
X118220Y-839589D01*
Y-839755D01*
X118093Y-839839D01*
G01Y-837589D02*
X117966Y-837505D01*
Y-837339D01*
X118093Y-837255D01*
X118220Y-837339D01*
Y-837505D01*
X118093Y-837589D01*
G01X122876Y-841339D02*
X122243Y-840505D01*
X121926Y-839672D01*
Y-836339D01*
X122243Y-835505D01*
X122876Y-834672D01*
G01X128293D02*
X127786Y-834839D01*
X127406Y-835255D01*
X127153Y-835755D01*
X126963Y-836422D01*
X126900Y-837172D01*
X126963Y-837922D01*
X127153Y-838589D01*
X127406Y-839089D01*
X127786Y-839505D01*
X128293Y-839672D01*
X128800Y-839505D01*
X129180Y-839089D01*
X129433Y-838589D01*
X129623Y-837922D01*
X129686Y-837172D01*
X129623Y-836422D01*
X129433Y-835755D01*
X129180Y-835255D01*
X128800Y-834839D01*
X128293Y-834672D01*
G01X132000Y-838672D02*
X132380Y-839255D01*
X132886Y-839589D01*
X133456Y-839672D01*
X133963Y-839589D01*
X134470Y-839172D01*
X134786Y-838672D01*
X134850Y-838172D01*
X134723Y-837589D01*
X134280Y-837172D01*
X133836Y-837005D01*
X133266D01*
G01X133836D02*
X134216Y-836755D01*
X134533Y-836339D01*
X134660Y-835839D01*
X134533Y-835339D01*
X134216Y-834922D01*
X133646Y-834672D01*
X133076Y-834755D01*
X132506Y-835089D01*
G01X138810Y-841339D02*
X139443Y-840505D01*
X139760Y-839672D01*
Y-836339D01*
X139443Y-835505D01*
X138810Y-834672D01*
G01X142200Y-838672D02*
X142580Y-839255D01*
X143086Y-839589D01*
X143656Y-839672D01*
X144163Y-839589D01*
X144670Y-839172D01*
X144986Y-838672D01*
X145050Y-838172D01*
X144923Y-837589D01*
X144480Y-837172D01*
X144036Y-837005D01*
X143466D01*
G01X144036D02*
X144416Y-836755D01*
X144733Y-836339D01*
X144860Y-835839D01*
X144733Y-835339D01*
X144416Y-834922D01*
X143846Y-834672D01*
X143276Y-834755D01*
X142706Y-835089D01*
G01X147616Y-839089D02*
X148060Y-839505D01*
X148566Y-839672D01*
X149073Y-839505D01*
X149516Y-839005D01*
X149833Y-838255D01*
X149960Y-837505D01*
Y-836589D01*
X149833Y-835839D01*
X149516Y-835172D01*
X149136Y-834839D01*
X148693Y-834672D01*
X148186Y-834839D01*
X147806Y-835172D01*
X147553Y-835672D01*
X147426Y-836339D01*
X147553Y-836922D01*
X147870Y-837505D01*
X148250Y-837839D01*
X148693Y-837922D01*
X149200Y-837755D01*
X149580Y-837339D01*
X149960Y-836589D01*
G01X153666Y-839672D02*
X153793Y-838589D01*
X153983Y-837672D01*
X154236Y-836839D01*
X154553Y-835922D01*
X155060Y-834672D01*
X152526D01*
G01X158070Y-838005D02*
X159716D01*
G01X162600Y-838672D02*
X162980Y-839255D01*
X163486Y-839589D01*
X164056Y-839672D01*
X164563Y-839589D01*
X165070Y-839172D01*
X165386Y-838672D01*
X165450Y-838172D01*
X165323Y-837589D01*
X164880Y-837172D01*
X164436Y-837005D01*
X163866D01*
G01X164436D02*
X164816Y-836755D01*
X165133Y-836339D01*
X165260Y-835839D01*
X165133Y-835339D01*
X164816Y-834922D01*
X164246Y-834672D01*
X163676Y-834755D01*
X163106Y-835089D01*
G01X167890Y-837589D02*
X168333Y-837005D01*
X168713Y-836672D01*
X169220Y-836505D01*
X169663Y-836672D01*
X169980Y-837005D01*
X170233Y-837505D01*
X170296Y-838089D01*
X170233Y-838589D01*
X169980Y-839089D01*
X169600Y-839505D01*
X169156Y-839672D01*
X168650Y-839505D01*
X168206Y-839005D01*
X167953Y-838255D01*
X167890Y-837422D01*
X168016Y-836339D01*
X168206Y-835755D01*
X168523Y-835172D01*
X168966Y-834755D01*
X169410Y-834672D01*
X169853Y-834839D01*
X170170Y-835255D01*
G01X174193Y-839672D02*
Y-834672D01*
X173433Y-835672D01*
G01Y-839672D02*
X174953D01*
G01X180053D02*
Y-834672D01*
X177710Y-838255D01*
X180876D01*
G01X199093Y-769672D02*
Y-844672D01*
G01Y-819672D02*
X302093D01*
Y-794672D01*
G01X199093D02*
X302093D01*
G01X309600Y-829672D02*
Y-824672D01*
X310866D01*
X311373Y-824922D01*
X311753Y-825255D01*
X312070Y-825755D01*
X312323Y-826339D01*
X312386Y-827172D01*
X312323Y-828005D01*
X312070Y-828589D01*
X311753Y-829089D01*
X311373Y-829422D01*
X310866Y-829672D01*
X309600D01*
G01X314510D02*
X316093Y-824672D01*
X317676Y-829672D01*
G01X317106Y-827922D02*
X315080D01*
G01X321193Y-824672D02*
Y-829672D01*
G01X319736Y-824672D02*
X322650D01*
G01X327560Y-829672D02*
X325026D01*
Y-824672D01*
X327560D01*
G01X326546Y-827089D02*
X325026D01*
G01X331393Y-829839D02*
X331266Y-829755D01*
Y-829589D01*
X331393Y-829505D01*
X331520Y-829589D01*
Y-829755D01*
X331393Y-829839D01*
G01Y-827589D02*
X331266Y-827505D01*
Y-827339D01*
X331393Y-827255D01*
X331520Y-827339D01*
Y-827505D01*
X331393Y-827589D01*
G01X304093Y-769672D02*
Y-844672D01*
G01X302093Y-769672D02*
Y-844672D01*
G01X304093Y-819672D02*
X504093D01*
G01X309726Y-804672D02*
Y-799672D01*
X311246D01*
X311753Y-799922D01*
X312133Y-800505D01*
X312260Y-801172D01*
X312133Y-801839D01*
X311816Y-802339D01*
X311246Y-802589D01*
X309726D01*
G01X314953Y-804839D02*
X317233Y-799672D01*
G01X319736Y-804672D02*
Y-799672D01*
X322650Y-804672D01*
Y-799672D01*
G01X326293Y-804839D02*
X326166Y-804755D01*
Y-804589D01*
X326293Y-804505D01*
X326420Y-804589D01*
Y-804755D01*
X326293Y-804839D01*
G01Y-802589D02*
X326166Y-802505D01*
Y-802339D01*
X326293Y-802255D01*
X326420Y-802339D01*
Y-802505D01*
X326293Y-802589D01*
G01X304093Y-794672D02*
X504093D01*
G01X309726Y-779672D02*
Y-774672D01*
X311246D01*
X311753Y-774922D01*
X312133Y-775505D01*
X312260Y-776172D01*
X312133Y-776839D01*
X311816Y-777339D01*
X311246Y-777589D01*
X309726D01*
G01X314826Y-779672D02*
Y-774672D01*
X316410D01*
X316916Y-774922D01*
X317233Y-775255D01*
X317360Y-775922D01*
X317233Y-776589D01*
X316853Y-777005D01*
X316410Y-777255D01*
X314826D01*
G01X316410D02*
X317360Y-779672D01*
G01X321193D02*
X320686Y-779589D01*
X320243Y-779255D01*
X319863Y-778755D01*
X319610Y-778172D01*
X319483Y-777505D01*
Y-776839D01*
X319610Y-776172D01*
X319863Y-775589D01*
X320243Y-775089D01*
X320686Y-774755D01*
X321193Y-774672D01*
X321700Y-774755D01*
X322143Y-775089D01*
X322523Y-775589D01*
X322776Y-776172D01*
X322903Y-776839D01*
Y-777505D01*
X322776Y-778172D01*
X322523Y-778755D01*
X322143Y-779255D01*
X321700Y-779589D01*
X321193Y-779672D01*
G01X325026Y-778672D02*
X325343Y-779172D01*
X325723Y-779505D01*
X326166Y-779672D01*
X326673Y-779505D01*
X327053Y-779172D01*
X327433Y-778672D01*
X327560Y-778005D01*
Y-774672D01*
G01X332660Y-779672D02*
X330126D01*
Y-774672D01*
X332660D01*
G01X331646Y-777089D02*
X330126D01*
G01X337886Y-775089D02*
X337506Y-774839D01*
X337063Y-774672D01*
X336556D01*
X335986Y-774922D01*
X335543Y-775339D01*
X335226Y-775839D01*
X334973Y-776672D01*
X334910Y-777422D01*
X335036Y-778172D01*
X335226Y-778672D01*
X335606Y-779172D01*
X336050Y-779505D01*
X336493Y-779672D01*
X336936D01*
X337380Y-779505D01*
X337760Y-779255D01*
X338076Y-778922D01*
G01X341593Y-774672D02*
Y-779672D01*
G01X340136Y-774672D02*
X343050D01*
G01X346693Y-779839D02*
X346566Y-779755D01*
Y-779589D01*
X346693Y-779505D01*
X346820Y-779589D01*
Y-779755D01*
X346693Y-779839D01*
G01Y-777589D02*
X346566Y-777505D01*
Y-777339D01*
X346693Y-777255D01*
X346820Y-777339D01*
Y-777505D01*
X346693Y-777589D01*
G01X419093Y-819672D02*
Y-844672D01*
G01X421726Y-822172D02*
Y-827172D01*
X424260D01*
G01X427333Y-822172D02*
X428853D01*
G01X428093D02*
Y-827172D01*
G01X427333D02*
X428853D01*
G01X433700Y-824505D02*
X433953Y-824255D01*
X434143Y-823839D01*
X434270Y-823255D01*
X434143Y-822755D01*
X433890Y-822422D01*
X433446Y-822172D01*
X431736D01*
Y-827172D01*
X433826D01*
X434270Y-826839D01*
X434523Y-826339D01*
X434650Y-825755D01*
X434523Y-825172D01*
X434143Y-824672D01*
X433700Y-824505D01*
X431736D01*
G01X438293Y-827339D02*
X438166Y-827255D01*
Y-827089D01*
X438293Y-827005D01*
X438420Y-827089D01*
Y-827255D01*
X438293Y-827339D01*
G01Y-825089D02*
X438166Y-825005D01*
Y-824839D01*
X438293Y-824755D01*
X438420Y-824839D01*
Y-825005D01*
X438293Y-825089D01*
G01X470106Y-847839D02*
X470213Y-847714D01*
X470293Y-847505D01*
X470346Y-847214D01*
X470293Y-846964D01*
X470186Y-846797D01*
X470000Y-846672D01*
X469280D01*
Y-849172D01*
X470160D01*
X470346Y-849005D01*
X470453Y-848755D01*
X470506Y-848464D01*
X470453Y-848172D01*
X470293Y-847922D01*
X470106Y-847839D01*
X469280D01*
G01X472573Y-849172D02*
Y-847505D01*
G01Y-847797D02*
X472466Y-847630D01*
X472306Y-847547D01*
X472120Y-847505D01*
X471933Y-847589D01*
X471773Y-847755D01*
X471666Y-848005D01*
X471613Y-848339D01*
X471666Y-848672D01*
X471773Y-848922D01*
X471933Y-849089D01*
X472120Y-849172D01*
X472306Y-849130D01*
X472466Y-849005D01*
X472573Y-848839D01*
G01X473893Y-848880D02*
X474026Y-849047D01*
X474213Y-849172D01*
X474373D01*
X474533Y-849089D01*
X474640Y-848964D01*
X474693Y-848797D01*
X474666Y-848547D01*
X474560Y-848422D01*
X474080Y-848172D01*
X473973Y-847880D01*
X474026Y-847672D01*
X474133Y-847547D01*
X474293Y-847505D01*
X474453Y-847547D01*
X474613Y-847672D01*
G01X476093Y-848047D02*
X476946D01*
X476866Y-847755D01*
X476733Y-847589D01*
X476546Y-847505D01*
X476360Y-847547D01*
X476200Y-847672D01*
X476093Y-847964D01*
X476040Y-848214D01*
Y-848464D01*
X476093Y-848714D01*
X476226Y-848964D01*
X476386Y-849130D01*
X476573Y-849172D01*
X476760Y-849089D01*
X476946Y-848839D01*
G01X478213Y-849172D02*
Y-846672D01*
G01Y-847922D02*
X478346Y-847672D01*
X478506Y-847547D01*
X478666Y-847505D01*
X478906Y-847589D01*
X479066Y-847755D01*
X479173Y-848047D01*
Y-848380D01*
X479120Y-848714D01*
X479013Y-848964D01*
X478826Y-849130D01*
X478666Y-849172D01*
X478506Y-849130D01*
X478346Y-849005D01*
X478213Y-848797D01*
G01X480893Y-849172D02*
X480733Y-849130D01*
X480573Y-848964D01*
X480466Y-848672D01*
X480413Y-848339D01*
X480466Y-848005D01*
X480573Y-847714D01*
X480733Y-847547D01*
X480893Y-847505D01*
X481053Y-847547D01*
X481213Y-847714D01*
X481320Y-848005D01*
X481346Y-848339D01*
X481320Y-848672D01*
X481213Y-848964D01*
X481053Y-849130D01*
X480893Y-849172D01*
G01X483573D02*
Y-847505D01*
G01Y-847797D02*
X483466Y-847630D01*
X483306Y-847547D01*
X483120Y-847505D01*
X482933Y-847589D01*
X482773Y-847755D01*
X482666Y-848005D01*
X482613Y-848339D01*
X482666Y-848672D01*
X482773Y-848922D01*
X482933Y-849089D01*
X483120Y-849172D01*
X483306Y-849130D01*
X483466Y-849005D01*
X483573Y-848839D01*
G01X484920Y-849172D02*
Y-847505D01*
G01Y-847839D02*
X485053Y-847672D01*
X485186Y-847547D01*
X485373Y-847505D01*
X485506Y-847547D01*
X485666Y-847672D01*
G01X487973Y-846672D02*
Y-849172D01*
G01Y-848797D02*
X487866Y-849005D01*
X487706Y-849130D01*
X487520Y-849172D01*
X487306Y-849089D01*
X487146Y-848880D01*
X487040Y-848630D01*
X487013Y-848339D01*
X487040Y-848047D01*
X487146Y-847797D01*
X487306Y-847589D01*
X487520Y-847505D01*
X487706Y-847547D01*
X487840Y-847630D01*
X487973Y-847797D01*
G01X491360Y-849172D02*
Y-846672D01*
X492026D01*
X492240Y-846797D01*
X492373Y-846964D01*
X492426Y-847297D01*
X492373Y-847630D01*
X492213Y-847839D01*
X492026Y-847964D01*
X491360D01*
G01X492026D02*
X492426Y-849172D01*
G01X493693Y-848047D02*
X494546D01*
X494466Y-847755D01*
X494333Y-847589D01*
X494146Y-847505D01*
X493960Y-847547D01*
X493800Y-847672D01*
X493693Y-847964D01*
X493640Y-848214D01*
Y-848464D01*
X493693Y-848714D01*
X493826Y-848964D01*
X493986Y-849130D01*
X494173Y-849172D01*
X494360Y-849089D01*
X494546Y-848839D01*
G01X495813Y-847505D02*
X496293Y-849172D01*
X496773Y-847505D01*
G01X498493Y-849255D02*
X498440Y-849214D01*
Y-849130D01*
X498493Y-849089D01*
X498546Y-849130D01*
Y-849214D01*
X498493Y-849255D01*
G01X500693Y-849172D02*
X500880Y-849130D01*
X501093Y-849005D01*
X501226Y-848797D01*
X501280Y-848505D01*
X501226Y-848214D01*
X501066Y-847964D01*
X500826Y-847839D01*
X500560D01*
X500400Y-847755D01*
X500266Y-847547D01*
X500213Y-847255D01*
X500293Y-846964D01*
X500480Y-846755D01*
X500693Y-846672D01*
X500906Y-846755D01*
X501093Y-846964D01*
X501173Y-847255D01*
X501120Y-847547D01*
X500986Y-847755D01*
X500826Y-847839D01*
X500560D01*
X500320Y-847964D01*
X500160Y-848214D01*
X500106Y-848505D01*
X500160Y-848797D01*
X500293Y-849005D01*
X500506Y-849130D01*
X500693Y-849172D01*
G01X503106Y-847839D02*
X503213Y-847714D01*
X503293Y-847505D01*
X503346Y-847214D01*
X503293Y-846964D01*
X503186Y-846797D01*
X503000Y-846672D01*
X502280D01*
Y-849172D01*
X503160D01*
X503346Y-849005D01*
X503453Y-848755D01*
X503506Y-848464D01*
X503453Y-848172D01*
X503293Y-847922D01*
X503106Y-847839D01*
X502280D01*
G01X465993Y-822172D02*
Y-827172D01*
G01X464536Y-822172D02*
X467450D01*
G01X471093Y-827172D02*
X470713Y-827089D01*
X470333Y-826755D01*
X470080Y-826172D01*
X469953Y-825505D01*
X470080Y-824839D01*
X470333Y-824255D01*
X470713Y-823922D01*
X471093Y-823839D01*
X471473Y-823922D01*
X471853Y-824255D01*
X472106Y-824839D01*
X472170Y-825505D01*
X472106Y-826172D01*
X471853Y-826755D01*
X471473Y-827089D01*
X471093Y-827172D01*
G01X476193D02*
X475813Y-827089D01*
X475433Y-826755D01*
X475180Y-826172D01*
X475053Y-825505D01*
X475180Y-824839D01*
X475433Y-824255D01*
X475813Y-823922D01*
X476193Y-823839D01*
X476573Y-823922D01*
X476953Y-824255D01*
X477206Y-824839D01*
X477270Y-825505D01*
X477206Y-826172D01*
X476953Y-826755D01*
X476573Y-827089D01*
X476193Y-827172D01*
G01X481293D02*
Y-822172D01*
G01X486393Y-827339D02*
X486266Y-827255D01*
Y-827089D01*
X486393Y-827005D01*
X486520Y-827089D01*
Y-827255D01*
X486393Y-827339D01*
G01Y-825089D02*
X486266Y-825005D01*
Y-824839D01*
X486393Y-824755D01*
X486520Y-824839D01*
Y-825005D01*
X486393Y-825089D01*
G01X462093Y-819672D02*
Y-844672D01*
G01Y-794672D02*
Y-819672D01*
G01X464726Y-802172D02*
Y-797172D01*
X466310D01*
X466816Y-797422D01*
X467133Y-797755D01*
X467260Y-798422D01*
X467133Y-799089D01*
X466753Y-799505D01*
X466310Y-799755D01*
X464726D01*
G01X466310D02*
X467260Y-802172D01*
G01X472360D02*
X469826D01*
Y-797172D01*
X472360D01*
G01X471346Y-799589D02*
X469826D01*
G01X474610Y-797172D02*
X476193Y-802172D01*
X477776Y-797172D01*
G01X481293Y-802339D02*
X481166Y-802255D01*
Y-802089D01*
X481293Y-802005D01*
X481420Y-802089D01*
Y-802255D01*
X481293Y-802339D01*
G01Y-800089D02*
X481166Y-800005D01*
Y-799839D01*
X481293Y-799755D01*
X481420Y-799839D01*
Y-800005D01*
X481293Y-800089D01*
G01X-297025Y-1013390D02*
Y1828909D01*
X3691357D01*
Y-1013390D01*
X-297025D01*
G01X16913Y-817022D02*
X18480D01*
Y-818912D01*
X18010Y-819542D01*
X17461Y-819962D01*
X16678Y-820172D01*
X15895Y-819962D01*
X15346Y-819542D01*
X14876Y-818912D01*
X14563Y-818177D01*
X14406Y-817337D01*
Y-816602D01*
X14563Y-815972D01*
X14876Y-815237D01*
X15346Y-814607D01*
X15816Y-814187D01*
X16443Y-813872D01*
X16991D01*
X17618Y-814082D01*
X18088Y-814502D01*
G01X21020Y-813872D02*
Y-818387D01*
X21333Y-819332D01*
X21960Y-819962D01*
X22743Y-820172D01*
X23526Y-819962D01*
X24153Y-819332D01*
X24466Y-818387D01*
Y-813872D01*
G01X28103D02*
X29983D01*
G01X29043D02*
Y-820172D01*
G01X28103D02*
X29983D01*
G01X33698Y-819332D02*
X34325Y-819857D01*
X35030Y-820172D01*
X35656D01*
X36283Y-819857D01*
X36753Y-819332D01*
X36988Y-818597D01*
X36831Y-817862D01*
X36440Y-817232D01*
X35735Y-816812D01*
X34795Y-816602D01*
X34246Y-816182D01*
X34011Y-815447D01*
X34168Y-814712D01*
X34560Y-814187D01*
X35108Y-813872D01*
X35656D01*
X36205Y-814082D01*
X36675Y-814607D01*
G01X39998Y-820172D02*
Y-813872D01*
G01X43288D02*
Y-820172D01*
G01Y-817022D02*
X39998D01*
G01X45985Y-820172D02*
X47943Y-813872D01*
X49901Y-820172D01*
G01X49196Y-817967D02*
X46690D01*
G01X52441Y-820172D02*
Y-813872D01*
X56045Y-820172D01*
Y-813872D01*
G01X65120Y-820172D02*
Y-813872D01*
X66686D01*
X67313Y-814187D01*
X67783Y-814607D01*
X68175Y-815237D01*
X68488Y-815972D01*
X68566Y-817022D01*
X68488Y-818072D01*
X68175Y-818807D01*
X67783Y-819437D01*
X67313Y-819857D01*
X66686Y-820172D01*
X65120D01*
G01X72203Y-813872D02*
X74083D01*
G01X73143D02*
Y-820172D01*
G01X72203D02*
X74083D01*
G01X77798Y-819332D02*
X78425Y-819857D01*
X79130Y-820172D01*
X79756D01*
X80383Y-819857D01*
X80853Y-819332D01*
X81088Y-818597D01*
X80931Y-817862D01*
X80540Y-817232D01*
X79835Y-816812D01*
X78895Y-816602D01*
X78346Y-816182D01*
X78111Y-815447D01*
X78268Y-814712D01*
X78660Y-814187D01*
X79208Y-813872D01*
X79756D01*
X80305Y-814082D01*
X80775Y-814607D01*
G01X85743Y-813872D02*
Y-820172D01*
G01X83941Y-813872D02*
X87545D01*
G01X92043Y-820382D02*
X91886Y-820277D01*
Y-820067D01*
X92043Y-819962D01*
X92200Y-820067D01*
Y-820277D01*
X92043Y-820382D01*
G01X98186Y-821327D02*
X98500Y-819962D01*
G01X104643Y-813872D02*
Y-820172D01*
G01X102841Y-813872D02*
X106445D01*
G01X108985Y-820172D02*
X110943Y-813872D01*
X112901Y-820172D01*
G01X112196Y-817967D02*
X109690D01*
G01X117243Y-820172D02*
X116616Y-820067D01*
X116068Y-819647D01*
X115598Y-819017D01*
X115285Y-818282D01*
X115128Y-817442D01*
Y-816602D01*
X115285Y-815762D01*
X115598Y-815027D01*
X116068Y-814397D01*
X116616Y-813977D01*
X117243Y-813872D01*
X117870Y-813977D01*
X118418Y-814397D01*
X118888Y-815027D01*
X119201Y-815762D01*
X119358Y-816602D01*
Y-817442D01*
X119201Y-818282D01*
X118888Y-819017D01*
X118418Y-819647D01*
X117870Y-820067D01*
X117243Y-820172D01*
G01X123543D02*
Y-817337D01*
X121976Y-813872D01*
G01X125110D02*
X123543Y-817337D01*
G01X128120Y-813872D02*
Y-818387D01*
X128433Y-819332D01*
X129060Y-819962D01*
X129843Y-820172D01*
X130626Y-819962D01*
X131253Y-819332D01*
X131566Y-818387D01*
Y-813872D01*
G01X134185Y-820172D02*
X136143Y-813872D01*
X138101Y-820172D01*
G01X137396Y-817967D02*
X134890D01*
G01X140641Y-820172D02*
Y-813872D01*
X144245Y-820172D01*
Y-813872D01*
G01X18166Y-824397D02*
X17696Y-824082D01*
X17148Y-823872D01*
X16521D01*
X15816Y-824187D01*
X15268Y-824712D01*
X14876Y-825342D01*
X14563Y-826392D01*
X14485Y-827337D01*
X14641Y-828282D01*
X14876Y-828912D01*
X15346Y-829542D01*
X15895Y-829962D01*
X16443Y-830172D01*
X16991D01*
X17540Y-829962D01*
X18010Y-829647D01*
X18401Y-829227D01*
G01X21803Y-823872D02*
X23683D01*
G01X22743D02*
Y-830172D01*
G01X21803D02*
X23683D01*
G01X29043Y-823872D02*
Y-830172D01*
G01X27241Y-823872D02*
X30845D01*
G01X35343Y-830172D02*
Y-827337D01*
X33776Y-823872D01*
G01X36910D02*
X35343Y-827337D01*
G01X46220Y-828912D02*
X46690Y-829647D01*
X47316Y-830067D01*
X48021Y-830172D01*
X48648Y-830067D01*
X49275Y-829542D01*
X49666Y-828912D01*
X49745Y-828282D01*
X49588Y-827547D01*
X49040Y-827022D01*
X48491Y-826812D01*
X47786D01*
G01X48491D02*
X48961Y-826497D01*
X49353Y-825972D01*
X49510Y-825342D01*
X49353Y-824712D01*
X48961Y-824187D01*
X48256Y-823872D01*
X47551Y-823977D01*
X46846Y-824397D01*
G01X52520Y-828912D02*
X52990Y-829647D01*
X53616Y-830067D01*
X54321Y-830172D01*
X54948Y-830067D01*
X55575Y-829542D01*
X55966Y-828912D01*
X56045Y-828282D01*
X55888Y-827547D01*
X55340Y-827022D01*
X54791Y-826812D01*
X54086D01*
G01X54791D02*
X55261Y-826497D01*
X55653Y-825972D01*
X55810Y-825342D01*
X55653Y-824712D01*
X55261Y-824187D01*
X54556Y-823872D01*
X53851Y-823977D01*
X53146Y-824397D01*
G01X58820Y-828912D02*
X59290Y-829647D01*
X59916Y-830067D01*
X60621Y-830172D01*
X61248Y-830067D01*
X61875Y-829542D01*
X62266Y-828912D01*
X62345Y-828282D01*
X62188Y-827547D01*
X61640Y-827022D01*
X61091Y-826812D01*
X60386D01*
G01X61091D02*
X61561Y-826497D01*
X61953Y-825972D01*
X62110Y-825342D01*
X61953Y-824712D01*
X61561Y-824187D01*
X60856Y-823872D01*
X60151Y-823977D01*
X59446Y-824397D01*
G01X66686Y-830172D02*
X66843Y-828807D01*
X67078Y-827652D01*
X67391Y-826602D01*
X67783Y-825447D01*
X68410Y-823872D01*
X65276D01*
G01X72986Y-830172D02*
X73143Y-828807D01*
X73378Y-827652D01*
X73691Y-826602D01*
X74083Y-825447D01*
X74710Y-823872D01*
X71576D01*
G01X79286Y-831327D02*
X79600Y-829962D01*
G01X85743Y-823872D02*
Y-830172D01*
G01X83941Y-823872D02*
X87545D01*
G01X90085Y-830172D02*
X92043Y-823872D01*
X94001Y-830172D01*
G01X93296Y-827967D02*
X90790D01*
G01X97403Y-823872D02*
X99283D01*
G01X98343D02*
Y-830172D01*
G01X97403D02*
X99283D01*
G01X102293Y-823872D02*
X103390Y-830172D01*
X104643Y-823872D01*
X105896Y-830172D01*
X106993Y-823872D01*
G01X108985Y-830172D02*
X110943Y-823872D01*
X112901Y-830172D01*
G01X112196Y-827967D02*
X109690D01*
G01X115441Y-830172D02*
Y-823872D01*
X119045Y-830172D01*
Y-823872D01*
G01X129451Y-832272D02*
X128668Y-831222D01*
X128276Y-830172D01*
Y-825972D01*
X128668Y-824922D01*
X129451Y-823872D01*
G01X140876Y-830172D02*
Y-823872D01*
X142835D01*
X143461Y-824187D01*
X143853Y-824607D01*
X144010Y-825447D01*
X143853Y-826287D01*
X143383Y-826812D01*
X142835Y-827127D01*
X140876D01*
G01X142835D02*
X144010Y-830172D01*
G01X148743Y-830382D02*
X148586Y-830277D01*
Y-830067D01*
X148743Y-829962D01*
X148900Y-830067D01*
Y-830277D01*
X148743Y-830382D01*
G01X155043Y-830172D02*
X154416Y-830067D01*
X153868Y-829647D01*
X153398Y-829017D01*
X153085Y-828282D01*
X152928Y-827442D01*
Y-826602D01*
X153085Y-825762D01*
X153398Y-825027D01*
X153868Y-824397D01*
X154416Y-823977D01*
X155043Y-823872D01*
X155670Y-823977D01*
X156218Y-824397D01*
X156688Y-825027D01*
X157001Y-825762D01*
X157158Y-826602D01*
Y-827442D01*
X157001Y-828282D01*
X156688Y-829017D01*
X156218Y-829647D01*
X155670Y-830067D01*
X155043Y-830172D01*
G01X161343Y-830382D02*
X161186Y-830277D01*
Y-830067D01*
X161343Y-829962D01*
X161500Y-830067D01*
Y-830277D01*
X161343Y-830382D01*
G01X169366Y-824397D02*
X168896Y-824082D01*
X168348Y-823872D01*
X167721D01*
X167016Y-824187D01*
X166468Y-824712D01*
X166076Y-825342D01*
X165763Y-826392D01*
X165685Y-827337D01*
X165841Y-828282D01*
X166076Y-828912D01*
X166546Y-829542D01*
X167095Y-829962D01*
X167643Y-830172D01*
X168191D01*
X168740Y-829962D01*
X169210Y-829647D01*
X169601Y-829227D01*
G01X173943Y-830382D02*
X173786Y-830277D01*
Y-830067D01*
X173943Y-829962D01*
X174100Y-830067D01*
Y-830277D01*
X173943Y-830382D01*
G01X180635Y-832272D02*
X181418Y-831222D01*
X181810Y-830172D01*
Y-825972D01*
X181418Y-824922D01*
X180635Y-823872D01*
G01X38743Y-799472D02*
X36223Y-799055D01*
X34018Y-797389D01*
X32128Y-794889D01*
X30868Y-791972D01*
X30238Y-788639D01*
Y-785305D01*
X30868Y-781972D01*
X32128Y-779055D01*
X34018Y-776556D01*
X36223Y-774889D01*
X38743Y-774472D01*
X41263Y-774889D01*
X43468Y-776556D01*
X45358Y-779055D01*
X46618Y-781972D01*
X47248Y-785305D01*
Y-788639D01*
X46618Y-791972D01*
X45358Y-794889D01*
X43468Y-797389D01*
X41263Y-799055D01*
X38743Y-799472D01*
G01X41263Y-792805D02*
X45043Y-799472D01*
G01X58588Y-782806D02*
Y-794472D01*
X59848Y-797389D01*
X61738Y-799055D01*
X63943Y-799472D01*
X66148Y-799055D01*
X68038Y-797389D01*
X69298Y-794472D01*
G01Y-799472D02*
Y-782806D01*
G01X94813Y-799472D02*
Y-782806D01*
G01Y-785722D02*
X93553Y-784056D01*
X91663Y-783222D01*
X89458Y-782806D01*
X87253Y-783639D01*
X85363Y-785305D01*
X84103Y-787806D01*
X83473Y-791139D01*
X84103Y-794472D01*
X85363Y-796973D01*
X87253Y-798639D01*
X89458Y-799472D01*
X91663Y-799055D01*
X93553Y-797806D01*
X94813Y-796139D01*
G01X108988Y-799472D02*
Y-782806D01*
G01Y-786972D02*
X110248Y-784889D01*
X112138Y-783222D01*
X114658Y-782806D01*
X116863Y-783222D01*
X118753Y-784889D01*
X119698Y-787806D01*
Y-799472D01*
G01X139543Y-774472D02*
Y-799472D01*
G01X135133Y-782806D02*
X143953D01*
G01X170413Y-799472D02*
Y-782806D01*
G01Y-785722D02*
X169153Y-784056D01*
X167263Y-783222D01*
X165058Y-782806D01*
X162853Y-783639D01*
X160963Y-785305D01*
X159703Y-787806D01*
X159073Y-791139D01*
X159703Y-794472D01*
X160963Y-796973D01*
X162853Y-798639D01*
X165058Y-799472D01*
X167263Y-799055D01*
X169153Y-797806D01*
X170413Y-796139D01*
G01X14641Y-810172D02*
Y-803872D01*
X18245Y-810172D01*
Y-803872D01*
G01X22743Y-810172D02*
X22116Y-810067D01*
X21568Y-809647D01*
X21098Y-809017D01*
X20785Y-808282D01*
X20628Y-807442D01*
Y-806602D01*
X20785Y-805762D01*
X21098Y-805027D01*
X21568Y-804397D01*
X22116Y-803977D01*
X22743Y-803872D01*
X23370Y-803977D01*
X23918Y-804397D01*
X24388Y-805027D01*
X24701Y-805762D01*
X24858Y-806602D01*
Y-807442D01*
X24701Y-808282D01*
X24388Y-809017D01*
X23918Y-809647D01*
X23370Y-810067D01*
X22743Y-810172D01*
G01X29043Y-810382D02*
X28886Y-810277D01*
Y-810067D01*
X29043Y-809962D01*
X29200Y-810067D01*
Y-810277D01*
X29043Y-810382D01*
G01X33855Y-804922D02*
X34325Y-804292D01*
X34873Y-803977D01*
X35500Y-803872D01*
X36283Y-804082D01*
X36831Y-804607D01*
X36988Y-805237D01*
X36910Y-805867D01*
X36596Y-806392D01*
X35030Y-807442D01*
X34325Y-808177D01*
X33855Y-809227D01*
X33698Y-810172D01*
X36988D01*
G01X41643D02*
Y-803872D01*
X40703Y-805132D01*
G01Y-810172D02*
X42583D01*
G01X47943D02*
Y-803872D01*
X47003Y-805132D01*
G01Y-810172D02*
X48883D01*
G01X54086Y-811327D02*
X54400Y-809962D01*
G01X58193Y-803872D02*
X59290Y-810172D01*
X60543Y-803872D01*
X61796Y-810172D01*
X62893Y-803872D01*
G01X68410Y-810172D02*
X65276D01*
Y-803872D01*
X68410D01*
G01X67156Y-806917D02*
X65276D01*
G01X71341Y-810172D02*
Y-803872D01*
X74945Y-810172D01*
Y-803872D01*
G01X77798Y-810172D02*
Y-803872D01*
G01X81088D02*
Y-810172D01*
G01Y-807022D02*
X77798D01*
G01X84020Y-803872D02*
Y-808387D01*
X84333Y-809332D01*
X84960Y-809962D01*
X85743Y-810172D01*
X86526Y-809962D01*
X87153Y-809332D01*
X87466Y-808387D01*
Y-803872D01*
G01X90085Y-810172D02*
X92043Y-803872D01*
X94001Y-810172D01*
G01X93296Y-807967D02*
X90790D01*
G01X103155Y-804922D02*
X103625Y-804292D01*
X104173Y-803977D01*
X104800Y-803872D01*
X105583Y-804082D01*
X106131Y-804607D01*
X106288Y-805237D01*
X106210Y-805867D01*
X105896Y-806392D01*
X104330Y-807442D01*
X103625Y-808177D01*
X103155Y-809227D01*
X102998Y-810172D01*
X106288D01*
G01X109141D02*
Y-803872D01*
X112745Y-810172D01*
Y-803872D01*
G01X115520Y-810172D02*
Y-803872D01*
X117086D01*
X117713Y-804187D01*
X118183Y-804607D01*
X118575Y-805237D01*
X118888Y-805972D01*
X118966Y-807022D01*
X118888Y-808072D01*
X118575Y-808807D01*
X118183Y-809437D01*
X117713Y-809857D01*
X117086Y-810172D01*
X115520D01*
G01X128276D02*
Y-803872D01*
X130235D01*
X130861Y-804187D01*
X131253Y-804607D01*
X131410Y-805447D01*
X131253Y-806287D01*
X130783Y-806812D01*
X130235Y-807127D01*
X128276D01*
G01X130235D02*
X131410Y-810172D01*
G01X134420D02*
Y-803872D01*
X135986D01*
X136613Y-804187D01*
X137083Y-804607D01*
X137475Y-805237D01*
X137788Y-805972D01*
X137866Y-807022D01*
X137788Y-808072D01*
X137475Y-808807D01*
X137083Y-809437D01*
X136613Y-809857D01*
X135986Y-810172D01*
X134420D01*
G01X142443Y-810382D02*
X142286Y-810277D01*
Y-810067D01*
X142443Y-809962D01*
X142600Y-810067D01*
Y-810277D01*
X142443Y-810382D01*
G01X210093Y-779172D02*
Y-787172D01*
X214093D01*
G01X221893D02*
Y-781839D01*
G01Y-782772D02*
X221493Y-782239D01*
X220893Y-781972D01*
X220193Y-781839D01*
X219493Y-782105D01*
X218893Y-782639D01*
X218493Y-783439D01*
X218293Y-784505D01*
X218493Y-785572D01*
X218893Y-786372D01*
X219493Y-786905D01*
X220193Y-787172D01*
X220893Y-787039D01*
X221493Y-786639D01*
X221893Y-786106D01*
G01X225993Y-789572D02*
X226593Y-789839D01*
X227393Y-789572D01*
X227893Y-789039D01*
X228293Y-788372D01*
X228893Y-786239D01*
X230193Y-781839D01*
G01X226993D02*
X228893Y-786239D01*
G01X234593Y-783572D02*
X237793D01*
X237493Y-782639D01*
X236993Y-782105D01*
X236293Y-781839D01*
X235593Y-781972D01*
X234993Y-782372D01*
X234593Y-783305D01*
X234393Y-784106D01*
Y-784905D01*
X234593Y-785705D01*
X235093Y-786505D01*
X235693Y-787039D01*
X236393Y-787172D01*
X237093Y-786905D01*
X237793Y-786106D01*
G01X242693Y-787172D02*
Y-781839D01*
G01Y-782905D02*
X243193Y-782372D01*
X243693Y-781972D01*
X244393Y-781839D01*
X244893Y-781972D01*
X245493Y-782372D01*
G01X229193Y-829172D02*
X232993D01*
X229193Y-837172D01*
X232993D01*
G01X239093Y-831839D02*
Y-837172D01*
G01Y-829705D02*
X238893Y-829572D01*
Y-829305D01*
X239093Y-829172D01*
X239293Y-829305D01*
Y-829572D01*
X239093Y-829705D01*
G01X245793Y-834505D02*
X248393D01*
G01X253093Y-837172D02*
Y-829172D01*
X255493D01*
X256293Y-829572D01*
X256893Y-830505D01*
X257093Y-831572D01*
X256893Y-832639D01*
X256393Y-833439D01*
X255493Y-833839D01*
X253093D01*
G01X263093Y-831839D02*
Y-837172D01*
G01Y-829705D02*
X262893Y-829572D01*
Y-829305D01*
X263093Y-829172D01*
X263293Y-829305D01*
Y-829572D01*
X263093Y-829705D01*
G01X269393Y-837172D02*
Y-831839D01*
G01Y-833172D02*
X269793Y-832505D01*
X270393Y-831972D01*
X271193Y-831839D01*
X271893Y-831972D01*
X272493Y-832505D01*
X272793Y-833439D01*
Y-837172D01*
G01X277693Y-839172D02*
X278393Y-839705D01*
X279193Y-839839D01*
X279893Y-839705D01*
X280493Y-839039D01*
X280893Y-838105D01*
Y-831839D01*
G01Y-832905D02*
X280493Y-832372D01*
X279893Y-831972D01*
X279193Y-831839D01*
X278393Y-832105D01*
X277893Y-832639D01*
X277493Y-833572D01*
X277293Y-834505D01*
X277393Y-835305D01*
X277793Y-836239D01*
X278393Y-836905D01*
X279193Y-837172D01*
X279793Y-837039D01*
X280493Y-836505D01*
X280893Y-835972D01*
G01X221593Y-812172D02*
Y-804172D01*
X223993D01*
X224793Y-804572D01*
X225393Y-805505D01*
X225593Y-806572D01*
X225393Y-807639D01*
X224893Y-808439D01*
X223993Y-808839D01*
X221593D01*
G01X229093Y-812172D02*
X231593Y-804172D01*
X234093Y-812172D01*
G01X233193Y-809372D02*
X229993D01*
G01X237493Y-811106D02*
X238293Y-811772D01*
X239193Y-812172D01*
X239993D01*
X240793Y-811772D01*
X241393Y-811106D01*
X241693Y-810172D01*
X241493Y-809239D01*
X240993Y-808439D01*
X240093Y-807905D01*
X238893Y-807639D01*
X238193Y-807105D01*
X237893Y-806172D01*
X238093Y-805239D01*
X238593Y-804572D01*
X239293Y-804172D01*
X239993D01*
X240693Y-804439D01*
X241293Y-805105D01*
G01X247593Y-804172D02*
Y-812172D01*
G01X245293Y-804172D02*
X249893D01*
G01X254293Y-809505D02*
X256893D01*
G01X263593Y-804172D02*
Y-812172D01*
G01X261293Y-804172D02*
X265893D01*
G01X271593Y-812172D02*
X270793Y-812039D01*
X270093Y-811505D01*
X269493Y-810705D01*
X269093Y-809772D01*
X268893Y-808705D01*
Y-807639D01*
X269093Y-806572D01*
X269493Y-805639D01*
X270093Y-804839D01*
X270793Y-804305D01*
X271593Y-804172D01*
X272393Y-804305D01*
X273093Y-804839D01*
X273693Y-805639D01*
X274093Y-806572D01*
X274293Y-807639D01*
Y-808705D01*
X274093Y-809772D01*
X273693Y-810705D01*
X273093Y-811505D01*
X272393Y-812039D01*
X271593Y-812172D01*
G01X277593D02*
Y-804172D01*
X279993D01*
X280793Y-804572D01*
X281393Y-805505D01*
X281593Y-806572D01*
X281393Y-807639D01*
X280893Y-808439D01*
X279993Y-808839D01*
X277593D01*
G01X336693Y-830505D02*
X337293Y-829705D01*
X337993Y-829305D01*
X338793Y-829172D01*
X339793Y-829439D01*
X340493Y-830105D01*
X340693Y-830905D01*
X340593Y-831706D01*
X340193Y-832372D01*
X338193Y-833705D01*
X337293Y-834639D01*
X336693Y-835972D01*
X336493Y-837172D01*
X340693D01*
G01X346593Y-829172D02*
X345793Y-829439D01*
X345193Y-830105D01*
X344793Y-830905D01*
X344493Y-831972D01*
X344393Y-833172D01*
X344493Y-834372D01*
X344793Y-835439D01*
X345193Y-836239D01*
X345793Y-836905D01*
X346593Y-837172D01*
X347393Y-836905D01*
X347993Y-836239D01*
X348393Y-835439D01*
X348693Y-834372D01*
X348793Y-833172D01*
X348693Y-831972D01*
X348393Y-830905D01*
X347993Y-830105D01*
X347393Y-829439D01*
X346593Y-829172D01*
G01X352693Y-830505D02*
X353293Y-829705D01*
X353993Y-829305D01*
X354793Y-829172D01*
X355793Y-829439D01*
X356493Y-830105D01*
X356693Y-830905D01*
X356593Y-831706D01*
X356193Y-832372D01*
X354193Y-833705D01*
X353293Y-834639D01*
X352693Y-835972D01*
X352493Y-837172D01*
X356693D01*
G01X360693Y-830505D02*
X361293Y-829705D01*
X361993Y-829305D01*
X362793Y-829172D01*
X363793Y-829439D01*
X364493Y-830105D01*
X364693Y-830905D01*
X364593Y-831706D01*
X364193Y-832372D01*
X362193Y-833705D01*
X361293Y-834639D01*
X360693Y-835972D01*
X360493Y-837172D01*
X364693D01*
G01X368793Y-837439D02*
X372393Y-829172D01*
G01X378593Y-837172D02*
Y-829172D01*
X377393Y-830772D01*
G01Y-837172D02*
X379793D01*
G01X384693Y-830505D02*
X385293Y-829705D01*
X385993Y-829305D01*
X386793Y-829172D01*
X387793Y-829439D01*
X388493Y-830105D01*
X388693Y-830905D01*
X388593Y-831706D01*
X388193Y-832372D01*
X386193Y-833705D01*
X385293Y-834639D01*
X384693Y-835972D01*
X384493Y-837172D01*
X388693D01*
G01X392793Y-837439D02*
X396393Y-829172D01*
G01X402593D02*
X401793Y-829439D01*
X401193Y-830105D01*
X400793Y-830905D01*
X400493Y-831972D01*
X400393Y-833172D01*
X400493Y-834372D01*
X400793Y-835439D01*
X401193Y-836239D01*
X401793Y-836905D01*
X402593Y-837172D01*
X403393Y-836905D01*
X403993Y-836239D01*
X404393Y-835439D01*
X404693Y-834372D01*
X404793Y-833172D01*
X404693Y-831972D01*
X404393Y-830905D01*
X403993Y-830105D01*
X403393Y-829439D01*
X402593Y-829172D01*
G01X408693Y-830505D02*
X409293Y-829705D01*
X409993Y-829305D01*
X410793Y-829172D01*
X411793Y-829439D01*
X412493Y-830105D01*
X412693Y-830905D01*
X412593Y-831706D01*
X412193Y-832372D01*
X410193Y-833705D01*
X409293Y-834639D01*
X408693Y-835972D01*
X408493Y-837172D01*
X412693D01*
G01X336393Y-814672D02*
Y-806672D01*
X338393D01*
X339193Y-807072D01*
X339793Y-807605D01*
X340293Y-808405D01*
X340693Y-809339D01*
X340793Y-810672D01*
X340693Y-812005D01*
X340293Y-812939D01*
X339793Y-813739D01*
X339193Y-814272D01*
X338393Y-814672D01*
X336393D01*
G01X344093D02*
X346593Y-806672D01*
X349093Y-814672D01*
G01X348193Y-811872D02*
X344993D01*
G01X354593Y-806672D02*
X353793Y-806939D01*
X353193Y-807605D01*
X352793Y-808405D01*
X352493Y-809472D01*
X352393Y-810672D01*
X352493Y-811872D01*
X352793Y-812939D01*
X353193Y-813739D01*
X353793Y-814405D01*
X354593Y-814672D01*
X355393Y-814405D01*
X355993Y-813739D01*
X356393Y-812939D01*
X356693Y-811872D01*
X356793Y-810672D01*
X356693Y-809472D01*
X356393Y-808405D01*
X355993Y-807605D01*
X355393Y-806939D01*
X354593Y-806672D01*
G01X360693Y-814672D02*
Y-806672D01*
X364493D01*
G01X363093Y-810539D02*
X360693D01*
G01X370593Y-806672D02*
X369793Y-806939D01*
X369193Y-807605D01*
X368793Y-808405D01*
X368493Y-809472D01*
X368393Y-810672D01*
X368493Y-811872D01*
X368793Y-812939D01*
X369193Y-813739D01*
X369793Y-814405D01*
X370593Y-814672D01*
X371393Y-814405D01*
X371993Y-813739D01*
X372393Y-812939D01*
X372693Y-811872D01*
X372793Y-810672D01*
X372693Y-809472D01*
X372393Y-808405D01*
X371993Y-807605D01*
X371393Y-806939D01*
X370593Y-806672D01*
G01X378593D02*
Y-814672D01*
G01X376293Y-806672D02*
X380893D01*
G01X384593Y-814672D02*
Y-806672D01*
X386993D01*
X387793Y-807072D01*
X388393Y-808005D01*
X388593Y-809072D01*
X388393Y-810139D01*
X387893Y-810939D01*
X386993Y-811339D01*
X384593D01*
G01X395393Y-810405D02*
X395793Y-810005D01*
X396093Y-809339D01*
X396293Y-808405D01*
X396093Y-807605D01*
X395693Y-807072D01*
X394993Y-806672D01*
X392293D01*
Y-814672D01*
X395593D01*
X396293Y-814139D01*
X396693Y-813339D01*
X396893Y-812405D01*
X396693Y-811472D01*
X396093Y-810672D01*
X395393Y-810405D01*
X392293D01*
G01X400093Y-814672D02*
X402593Y-806672D01*
X405093Y-814672D01*
G01X404193Y-811872D02*
X400993D01*
G01X408693Y-814672D02*
Y-806672D01*
X412493D01*
G01X411093Y-810539D02*
X408693D01*
G01X418593Y-806672D02*
X417793Y-806939D01*
X417193Y-807605D01*
X416793Y-808405D01*
X416493Y-809472D01*
X416393Y-810672D01*
X416493Y-811872D01*
X416793Y-812939D01*
X417193Y-813739D01*
X417793Y-814405D01*
X418593Y-814672D01*
X419393Y-814405D01*
X419993Y-813739D01*
X420393Y-812939D01*
X420693Y-811872D01*
X420793Y-810672D01*
X420693Y-809472D01*
X420393Y-808405D01*
X419993Y-807605D01*
X419393Y-806939D01*
X418593Y-806672D01*
G01X356693Y-787172D02*
Y-779172D01*
X360493D01*
G01X359093Y-783039D02*
X356693D01*
G01X366593Y-779172D02*
X365793Y-779439D01*
X365193Y-780105D01*
X364793Y-780905D01*
X364493Y-781972D01*
X364393Y-783172D01*
X364493Y-784372D01*
X364793Y-785439D01*
X365193Y-786239D01*
X365793Y-786905D01*
X366593Y-787172D01*
X367393Y-786905D01*
X367993Y-786239D01*
X368393Y-785439D01*
X368693Y-784372D01*
X368793Y-783172D01*
X368693Y-781972D01*
X368393Y-780905D01*
X367993Y-780105D01*
X367393Y-779439D01*
X366593Y-779172D01*
G01X374593D02*
Y-787172D01*
G01X372293Y-779172D02*
X376893D01*
G01X379593Y-789839D02*
X385593D01*
G01X388593Y-787172D02*
Y-779172D01*
X390993D01*
X391793Y-779572D01*
X392393Y-780505D01*
X392593Y-781572D01*
X392393Y-782639D01*
X391893Y-783439D01*
X390993Y-783839D01*
X388593D01*
G01X396393Y-787172D02*
Y-779172D01*
X398393D01*
X399193Y-779572D01*
X399793Y-780105D01*
X400293Y-780905D01*
X400693Y-781839D01*
X400793Y-783172D01*
X400693Y-784505D01*
X400293Y-785439D01*
X399793Y-786239D01*
X399193Y-786772D01*
X398393Y-787172D01*
X396393D01*
G01X407393Y-782905D02*
X407793Y-782505D01*
X408093Y-781839D01*
X408293Y-780905D01*
X408093Y-780105D01*
X407693Y-779572D01*
X406993Y-779172D01*
X404293D01*
Y-787172D01*
X407593D01*
X408293Y-786639D01*
X408693Y-785839D01*
X408893Y-784905D01*
X408693Y-783972D01*
X408093Y-783172D01*
X407393Y-782905D01*
X404293D01*
G01X411593Y-789839D02*
X417593D01*
G01X424793Y-779839D02*
X424193Y-779439D01*
X423493Y-779172D01*
X422693D01*
X421793Y-779572D01*
X421093Y-780239D01*
X420593Y-781039D01*
X420193Y-782372D01*
X420093Y-783572D01*
X420293Y-784772D01*
X420593Y-785572D01*
X421193Y-786372D01*
X421893Y-786905D01*
X422593Y-787172D01*
X423293D01*
X423993Y-786905D01*
X424593Y-786505D01*
X425093Y-785972D01*
G01X430593Y-787172D02*
X429793Y-787039D01*
X429093Y-786505D01*
X428493Y-785705D01*
X428093Y-784772D01*
X427893Y-783705D01*
Y-782639D01*
X428093Y-781572D01*
X428493Y-780639D01*
X429093Y-779839D01*
X429793Y-779305D01*
X430593Y-779172D01*
X431393Y-779305D01*
X432093Y-779839D01*
X432693Y-780639D01*
X433093Y-781572D01*
X433293Y-782639D01*
Y-783705D01*
X433093Y-784772D01*
X432693Y-785705D01*
X432093Y-786505D01*
X431393Y-787039D01*
X430593Y-787172D01*
G01X436293D02*
Y-779172D01*
X440893Y-787172D01*
Y-779172D01*
G01X444093D02*
X446593Y-787172D01*
X449093Y-779172D01*
G01X456593Y-787172D02*
X452593D01*
Y-779172D01*
X456593D01*
G01X454993Y-783039D02*
X452593D01*
G01X460593Y-787172D02*
Y-779172D01*
X463093D01*
X463893Y-779572D01*
X464393Y-780105D01*
X464593Y-781172D01*
X464393Y-782239D01*
X463793Y-782905D01*
X463093Y-783305D01*
X460593D01*
G01X463093D02*
X464593Y-787172D01*
G01X470593Y-779172D02*
Y-787172D01*
G01X468293Y-779172D02*
X472893D01*
G01X480593Y-787172D02*
X476593D01*
Y-779172D01*
X480593D01*
G01X478993Y-783039D02*
X476593D01*
G01X484593Y-787172D02*
Y-779172D01*
X487093D01*
X487893Y-779572D01*
X488393Y-780105D01*
X488593Y-781172D01*
X488393Y-782239D01*
X487793Y-782905D01*
X487093Y-783305D01*
X484593D01*
G01X487093D02*
X488593Y-787172D01*
G01X425093Y-840172D02*
Y-832172D01*
X423893Y-833772D01*
G01Y-840172D02*
X426293D01*
G01X431193Y-836839D02*
X431893Y-835905D01*
X432493Y-835372D01*
X433293Y-835105D01*
X433993Y-835372D01*
X434493Y-835905D01*
X434893Y-836705D01*
X434993Y-837639D01*
X434893Y-838439D01*
X434493Y-839239D01*
X433893Y-839905D01*
X433193Y-840172D01*
X432393Y-839905D01*
X431693Y-839106D01*
X431293Y-837905D01*
X431193Y-836572D01*
X431393Y-834839D01*
X431693Y-833905D01*
X432193Y-832972D01*
X432893Y-832305D01*
X433593Y-832172D01*
X434293Y-832439D01*
X434793Y-833105D01*
G01X441093Y-840439D02*
X440893Y-840305D01*
Y-840039D01*
X441093Y-839905D01*
X441293Y-840039D01*
Y-840305D01*
X441093Y-840439D01*
G01X447193Y-836839D02*
X447893Y-835905D01*
X448493Y-835372D01*
X449293Y-835105D01*
X449993Y-835372D01*
X450493Y-835905D01*
X450893Y-836705D01*
X450993Y-837639D01*
X450893Y-838439D01*
X450493Y-839239D01*
X449893Y-839905D01*
X449193Y-840172D01*
X448393Y-839905D01*
X447693Y-839106D01*
X447293Y-837905D01*
X447193Y-836572D01*
X447393Y-834839D01*
X447693Y-833905D01*
X448193Y-832972D01*
X448893Y-832305D01*
X449593Y-832172D01*
X450293Y-832439D01*
X450793Y-833105D01*
G01X470093Y-840172D02*
Y-832172D01*
X468893Y-833772D01*
G01Y-840172D02*
X471293D01*
G01X477893D02*
X478093Y-838439D01*
X478393Y-836972D01*
X478793Y-835639D01*
X479293Y-834172D01*
X480093Y-832172D01*
X476093D01*
G01X486093Y-840439D02*
X485893Y-840305D01*
Y-840039D01*
X486093Y-839905D01*
X486293Y-840039D01*
Y-840305D01*
X486093Y-840439D01*
G01X492193Y-833505D02*
X492793Y-832705D01*
X493493Y-832305D01*
X494293Y-832172D01*
X495293Y-832439D01*
X495993Y-833105D01*
X496193Y-833905D01*
X496093Y-834706D01*
X495693Y-835372D01*
X493693Y-836705D01*
X492793Y-837639D01*
X492193Y-838972D01*
X491993Y-840172D01*
X496193D01*
G01X490193Y-815172D02*
Y-807172D01*
X493993D01*
G01X492593Y-811039D02*
X490193D01*
G54D59*
X832799Y337500D03*
X820201D03*
Y368600D03*
X832799D03*
Y360600D03*
X820201D03*
Y345500D03*
X832799D03*
G54D68*
X1025068Y151940D03*
Y173594D03*
X1052040Y151940D03*
Y173594D03*
G54D77*
X1124598Y166699D03*
G54D69*
X1041507Y149381D03*
X1039538D03*
X1037570D03*
X1035601D03*
Y176153D03*
X1037570D03*
X1039538D03*
X1041507D03*
X1047412Y149381D03*
X1045444D03*
X1043475D03*
Y176153D03*
X1045444D03*
X1047412D03*
G54D78*
X1116518Y159809D03*
Y157839D03*
Y155869D03*
Y177529D03*
Y175559D03*
Y173589D03*
Y171619D03*
Y169649D03*
Y167679D03*
Y165719D03*
Y163749D03*
Y161779D03*
X1147618Y155869D03*
Y157839D03*
Y159809D03*
Y161779D03*
Y163749D03*
Y165719D03*
Y167679D03*
Y169649D03*
Y171619D03*
Y173589D03*
Y175559D03*
Y177529D03*
G54D79*
X1119268Y153119D03*
X1121238D03*
X1123208D03*
X1125178D03*
X1127148D03*
X1129118D03*
X1131088D03*
Y180279D03*
X1129118D03*
X1127148D03*
X1125178D03*
X1123208D03*
X1121238D03*
X1119268D03*
X1136988Y153119D03*
X1138958D03*
X1140928D03*
X1142898D03*
X1144868D03*
Y180279D03*
X1142898D03*
X1140928D03*
X1138958D03*
X1136988D03*
M02*
